FILE_TYPE = MACRO_DRAWING;
SET COLOR_WIRE YELLOW;
SET COLOR_PROP ORANGE;
SET COLOR_DOT WHITE;
SET COLOR_ARC YELLOW;
SET COLOR_BODY GREEN;
SET COLOR_NOTE PURPLE;
SET PROP_DISPLAY VALUE;
SET PAGE_NUMBER P24;
FORCEADD OFFPAGE..2
R 2
(-1725 -125);
FORCEPROP 2 LAST $XR1 91 
J 0
(-2069 -125);
DISPLAY 0.638298 (-2069 -125);
PAINT MONO (-2069 -125);
FORCEPROP 2 LAST $XR0 90 
J 0
(-1979 -125);
DISPLAY 0.638298 (-1979 -125);
PAINT MONO (-1979 -125);
FORCEPROP 2 LAST CDS_LIB standard
J 0
(-1725 -125);
PAINT MONO (-1725 -125);
DISPLAY INVISIBLE (-1725 -125);
FORCEPROP 1 LAST OFFPAGE TRUE
J 2
(-2050 -250);
DISPLAY 0.872340 (-2050 -250);
DISPLAY INVISIBLE (-2050 -250);
FORCEPROP 1 LAST COMMENT_BODY TRUE
J 2
(-1680 -220);
DISPLAY 0.872340 (-1680 -220);
PAINT GREEN (-1680 -220);
DISPLAY INVISIBLE (-1680 -220);
FORCEPROP 2 LAST PATH I1
J 0
(-1675 -50);
DISPLAY 1.021277 (-1675 -50);
DISPLAY INVISIBLE (-1675 -50);
FORCEADD OFFPAGE..3
R 2
(-1725 2025);
FORCEPROP 2 LAST $XR1 91 
J 0
(-2094 2025);
DISPLAY 0.638298 (-2094 2025);
PAINT MONO (-2094 2025);
FORCEPROP 2 LAST $XR0 90 
J 0
(-2004 2025);
DISPLAY 0.638298 (-2004 2025);
PAINT MONO (-2004 2025);
FORCEPROP 2 LAST CDS_LIB standard
J 0
(-1725 2025);
DISPLAY INVISIBLE (-1725 2025);
FORCEPROP 1 LAST OFFPAGE TRUE
J 2
(-2050 1900);
DISPLAY 0.872340 (-2050 1900);
DISPLAY INVISIBLE (-2050 1900);
FORCEPROP 1 LAST COMMENT_BODY TRUE
J 2
(-1675 1925);
DISPLAY 0.872340 (-1675 1925);
PAINT GREEN (-1675 1925);
DISPLAY INVISIBLE (-1675 1925);
FORCEPROP 2 LAST PATH I10
J 0
(-1675 2100);
DISPLAY 1.021277 (-1675 2100);
DISPLAY INVISIBLE (-1675 2100);
FORCEADD TAP..1
(2725 400);
FORCEPROP 3 LASTPIN (2675 400) SIG_NAME M_E_CPU0_SB_CS_N<3>
J 0
(2685 410);
DISPLAY 0.659574 (2685 410);
PAINT MONO (2685 410);
DISPLAY INVISIBLE (2685 410);
FORCEPROP 1 LASTPIN (2675 400) BN 3
J 0
(2663 408);
DISPLAY 0.680851 (2663 408);
PAINT GREEN (2663 408);
FORCEPROP 2 LAST CDS_LIB standard
J 0
(2725 400);
DISPLAY INVISIBLE (2725 400);
FORCEPROP 1 LAST BODY_TYPE PLUMBING
J 0
(2725 450);
DISPLAY 0.872340 (2725 450);
PAINT GREEN (2725 450);
DISPLAY INVISIBLE (2725 450);
FORCEPROP 1 LAST HDL_TAP TRUE
J 0
(3050 275);
DISPLAY 0.872340 (3050 275);
DISPLAY INVISIBLE (3050 275);
FORCEPROP 1 LAST PATH I100
J 0
(2723 400);
DISPLAY 0.872340 (2723 400);
PAINT GREEN (2723 400);
DISPLAY INVISIBLE (2723 400);
FORCEADD TAP..1
(2725 600);
FORCEPROP 3 LASTPIN (2675 600) SIG_NAME M_E_CPU0_SA_CS_N<1>
J 0
(2685 610);
DISPLAY 0.659574 (2685 610);
PAINT MONO (2685 610);
DISPLAY INVISIBLE (2685 610);
FORCEPROP 1 LASTPIN (2675 600) BN 1
J 0
(2663 608);
DISPLAY 0.680851 (2663 608);
PAINT GREEN (2663 608);
FORCEPROP 2 LAST CDS_LIB standard
J 0
(2725 600);
DISPLAY INVISIBLE (2725 600);
FORCEPROP 1 LAST BODY_TYPE PLUMBING
J 0
(2725 650);
DISPLAY 0.872340 (2725 650);
PAINT GREEN (2725 650);
DISPLAY INVISIBLE (2725 650);
FORCEPROP 1 LAST HDL_TAP TRUE
J 0
(3050 475);
DISPLAY 0.872340 (3050 475);
DISPLAY INVISIBLE (3050 475);
FORCEPROP 1 LAST PATH I101
J 0
(2723 600);
DISPLAY 0.872340 (2723 600);
PAINT GREEN (2723 600);
DISPLAY INVISIBLE (2723 600);
FORCEADD TAP..1
(2725 550);
FORCEPROP 3 LASTPIN (2675 550) SIG_NAME M_E_CPU0_SA_CS_N<0>
J 0
(2685 560);
DISPLAY 0.659574 (2685 560);
PAINT MONO (2685 560);
DISPLAY INVISIBLE (2685 560);
FORCEPROP 1 LASTPIN (2675 550) BN 0
J 0
(2663 558);
DISPLAY 0.680851 (2663 558);
PAINT GREEN (2663 558);
FORCEPROP 2 LAST CDS_LIB standard
J 0
(2725 550);
DISPLAY INVISIBLE (2725 550);
FORCEPROP 1 LAST BODY_TYPE PLUMBING
J 0
(2725 600);
DISPLAY 0.872340 (2725 600);
PAINT GREEN (2725 600);
DISPLAY INVISIBLE (2725 600);
FORCEPROP 1 LAST HDL_TAP TRUE
J 0
(3050 425);
DISPLAY 0.872340 (3050 425);
DISPLAY INVISIBLE (3050 425);
FORCEPROP 1 LAST PATH I102
J 0
(2723 550);
DISPLAY 0.872340 (2723 550);
PAINT GREEN (2723 550);
DISPLAY INVISIBLE (2723 550);
FORCEADD TAP..1
(2725 650);
FORCEPROP 3 LASTPIN (2675 650) SIG_NAME M_E_CPU0_SA_CS_N<2>
J 0
(2685 660);
DISPLAY 0.659574 (2685 660);
PAINT MONO (2685 660);
DISPLAY INVISIBLE (2685 660);
FORCEPROP 1 LASTPIN (2675 650) BN 2
J 0
(2663 658);
DISPLAY 0.680851 (2663 658);
PAINT GREEN (2663 658);
FORCEPROP 2 LAST CDS_LIB standard
J 0
(2725 650);
DISPLAY INVISIBLE (2725 650);
FORCEPROP 1 LAST BODY_TYPE PLUMBING
J 0
(2725 700);
DISPLAY 0.872340 (2725 700);
PAINT GREEN (2725 700);
DISPLAY INVISIBLE (2725 700);
FORCEPROP 1 LAST HDL_TAP TRUE
J 0
(3050 525);
DISPLAY 0.872340 (3050 525);
DISPLAY INVISIBLE (3050 525);
FORCEPROP 1 LAST PATH I103
J 0
(2723 650);
DISPLAY 0.872340 (2723 650);
PAINT GREEN (2723 650);
DISPLAY INVISIBLE (2723 650);
FORCEADD TAP..1
(2725 700);
FORCEPROP 3 LASTPIN (2675 700) SIG_NAME M_E_CPU0_SA_CS_N<3>
J 0
(2685 710);
DISPLAY 0.659574 (2685 710);
PAINT MONO (2685 710);
DISPLAY INVISIBLE (2685 710);
FORCEPROP 1 LASTPIN (2675 700) BN 3
J 0
(2663 708);
DISPLAY 0.680851 (2663 708);
PAINT GREEN (2663 708);
FORCEPROP 2 LAST CDS_LIB standard
J 0
(2725 700);
DISPLAY INVISIBLE (2725 700);
FORCEPROP 1 LAST BODY_TYPE PLUMBING
J 0
(2725 750);
DISPLAY 0.872340 (2725 750);
PAINT GREEN (2725 750);
DISPLAY INVISIBLE (2725 750);
FORCEPROP 1 LAST HDL_TAP TRUE
J 0
(3050 575);
DISPLAY 0.872340 (3050 575);
DISPLAY INVISIBLE (3050 575);
FORCEPROP 1 LAST PATH I104
J 0
(2723 700);
DISPLAY 0.872340 (2723 700);
PAINT GREEN (2723 700);
DISPLAY INVISIBLE (2723 700);
FORCEADD TAP..1
(2725 950);
FORCEPROP 3 LASTPIN (2675 950) SIG_NAME M_E_CPU0_SB_CA<1>
J 0
(2685 960);
DISPLAY 0.659574 (2685 960);
PAINT MONO (2685 960);
DISPLAY INVISIBLE (2685 960);
FORCEPROP 1 LASTPIN (2675 950) BN 1
J 0
(2663 958);
DISPLAY 0.680851 (2663 958);
PAINT GREEN (2663 958);
FORCEPROP 2 LAST CDS_LIB standard
J 0
(2725 950);
DISPLAY INVISIBLE (2725 950);
FORCEPROP 1 LAST BODY_TYPE PLUMBING
J 0
(2725 1000);
DISPLAY 0.872340 (2725 1000);
PAINT GREEN (2725 1000);
DISPLAY INVISIBLE (2725 1000);
FORCEPROP 1 LAST HDL_TAP TRUE
J 0
(3050 825);
DISPLAY 0.872340 (3050 825);
DISPLAY INVISIBLE (3050 825);
FORCEPROP 1 LAST PATH I105
J 0
(2723 950);
DISPLAY 0.872340 (2723 950);
PAINT GREEN (2723 950);
DISPLAY INVISIBLE (2723 950);
FORCEADD TAP..1
(2725 900);
FORCEPROP 3 LASTPIN (2675 900) SIG_NAME M_E_CPU0_SB_CA<0>
J 0
(2685 910);
DISPLAY 0.659574 (2685 910);
PAINT MONO (2685 910);
DISPLAY INVISIBLE (2685 910);
FORCEPROP 1 LASTPIN (2675 900) BN 0
J 0
(2663 908);
DISPLAY 0.680851 (2663 908);
PAINT GREEN (2663 908);
FORCEPROP 2 LAST CDS_LIB standard
J 0
(2725 900);
DISPLAY INVISIBLE (2725 900);
FORCEPROP 1 LAST BODY_TYPE PLUMBING
J 0
(2725 950);
DISPLAY 0.872340 (2725 950);
PAINT GREEN (2725 950);
DISPLAY INVISIBLE (2725 950);
FORCEPROP 1 LAST HDL_TAP TRUE
J 0
(3050 775);
DISPLAY 0.872340 (3050 775);
DISPLAY INVISIBLE (3050 775);
FORCEPROP 1 LAST PATH I106
J 0
(2723 900);
DISPLAY 0.872340 (2723 900);
PAINT GREEN (2723 900);
DISPLAY INVISIBLE (2723 900);
FORCEADD TAP..1
(2725 1050);
FORCEPROP 3 LASTPIN (2675 1050) SIG_NAME M_E_CPU0_SB_CA<3>
J 0
(2685 1060);
DISPLAY 0.659574 (2685 1060);
PAINT MONO (2685 1060);
DISPLAY INVISIBLE (2685 1060);
FORCEPROP 1 LASTPIN (2675 1050) BN 3
J 0
(2663 1058);
DISPLAY 0.680851 (2663 1058);
PAINT GREEN (2663 1058);
FORCEPROP 2 LAST CDS_LIB standard
J 0
(2725 1050);
DISPLAY INVISIBLE (2725 1050);
FORCEPROP 1 LAST BODY_TYPE PLUMBING
J 0
(2725 1100);
DISPLAY 0.872340 (2725 1100);
PAINT GREEN (2725 1100);
DISPLAY INVISIBLE (2725 1100);
FORCEPROP 1 LAST HDL_TAP TRUE
J 0
(3050 925);
DISPLAY 0.872340 (3050 925);
DISPLAY INVISIBLE (3050 925);
FORCEPROP 1 LAST PATH I107
J 0
(2723 1050);
DISPLAY 0.872340 (2723 1050);
PAINT GREEN (2723 1050);
DISPLAY INVISIBLE (2723 1050);
FORCEADD TAP..1
(2725 1100);
FORCEPROP 3 LASTPIN (2675 1100) SIG_NAME M_E_CPU0_SB_CA<4>
J 0
(2685 1110);
DISPLAY 0.659574 (2685 1110);
PAINT MONO (2685 1110);
DISPLAY INVISIBLE (2685 1110);
FORCEPROP 1 LASTPIN (2675 1100) BN 4
J 0
(2663 1108);
DISPLAY 0.680851 (2663 1108);
PAINT GREEN (2663 1108);
FORCEPROP 2 LAST CDS_LIB standard
J 0
(2725 1100);
DISPLAY INVISIBLE (2725 1100);
FORCEPROP 1 LAST BODY_TYPE PLUMBING
J 0
(2725 1150);
DISPLAY 0.872340 (2725 1150);
PAINT GREEN (2725 1150);
DISPLAY INVISIBLE (2725 1150);
FORCEPROP 1 LAST HDL_TAP TRUE
J 0
(3050 975);
DISPLAY 0.872340 (3050 975);
DISPLAY INVISIBLE (3050 975);
FORCEPROP 1 LAST PATH I108
J 0
(2723 1100);
DISPLAY 0.872340 (2723 1100);
PAINT GREEN (2723 1100);
DISPLAY INVISIBLE (2723 1100);
FORCEADD TAP..1
(2725 1000);
FORCEPROP 3 LASTPIN (2675 1000) SIG_NAME M_E_CPU0_SB_CA<2>
J 0
(2685 1010);
DISPLAY 0.659574 (2685 1010);
PAINT MONO (2685 1010);
DISPLAY INVISIBLE (2685 1010);
FORCEPROP 1 LASTPIN (2675 1000) BN 2
J 0
(2663 1008);
DISPLAY 0.680851 (2663 1008);
PAINT GREEN (2663 1008);
FORCEPROP 2 LAST CDS_LIB standard
J 0
(2725 1000);
DISPLAY INVISIBLE (2725 1000);
FORCEPROP 1 LAST BODY_TYPE PLUMBING
J 0
(2725 1050);
DISPLAY 0.872340 (2725 1050);
PAINT GREEN (2725 1050);
DISPLAY INVISIBLE (2725 1050);
FORCEPROP 1 LAST HDL_TAP TRUE
J 0
(3050 875);
DISPLAY 0.872340 (3050 875);
DISPLAY INVISIBLE (3050 875);
FORCEPROP 1 LAST PATH I109
J 0
(2723 1000);
DISPLAY 0.872340 (2723 1000);
PAINT GREEN (2723 1000);
DISPLAY INVISIBLE (2723 1000);
FORCEADD TAP..1
R 2
(-700 150);
FORCEPROP 3 LASTPIN (-650 150) SIG_NAME M_E_CPU0_SB_CB<2>
J 0
(-640 160);
DISPLAY 0.659574 (-640 160);
PAINT MONO (-640 160);
DISPLAY INVISIBLE (-640 160);
FORCEPROP 1 LASTPIN (-650 150) BN 2
J 2
(-638 158);
DISPLAY 0.680851 (-638 158);
PAINT GREEN (-638 158);
FORCEPROP 2 LAST CDS_LIB standard
J 0
(-700 150);
DISPLAY INVISIBLE (-700 150);
FORCEPROP 1 LAST BODY_TYPE PLUMBING
J 2
(-700 200);
DISPLAY 0.872340 (-700 200);
PAINT GREEN (-700 200);
DISPLAY INVISIBLE (-700 200);
FORCEPROP 1 LAST HDL_TAP TRUE
J 2
(-1025 25);
DISPLAY 0.872340 (-1025 25);
DISPLAY INVISIBLE (-1025 25);
FORCEPROP 1 LAST PATH I11
J 2
(-698 150);
DISPLAY 0.872340 (-698 150);
PAINT GREEN (-698 150);
DISPLAY INVISIBLE (-698 150);
FORCEADD TAP..1
(2725 1200);
FORCEPROP 3 LASTPIN (2675 1200) SIG_NAME M_E_CPU0_SB_CA<6>
J 0
(2685 1210);
DISPLAY 0.659574 (2685 1210);
PAINT MONO (2685 1210);
DISPLAY INVISIBLE (2685 1210);
FORCEPROP 1 LASTPIN (2675 1200) BN 6
J 0
(2663 1208);
DISPLAY 0.680851 (2663 1208);
PAINT GREEN (2663 1208);
FORCEPROP 2 LAST CDS_LIB standard
J 0
(2725 1200);
DISPLAY INVISIBLE (2725 1200);
FORCEPROP 1 LAST BODY_TYPE PLUMBING
J 0
(2725 1250);
DISPLAY 0.872340 (2725 1250);
PAINT GREEN (2725 1250);
DISPLAY INVISIBLE (2725 1250);
FORCEPROP 1 LAST HDL_TAP TRUE
J 0
(3050 1075);
DISPLAY 0.872340 (3050 1075);
DISPLAY INVISIBLE (3050 1075);
FORCEPROP 1 LAST PATH I110
J 0
(2723 1200);
DISPLAY 0.872340 (2723 1200);
PAINT GREEN (2723 1200);
DISPLAY INVISIBLE (2723 1200);
FORCEADD TAP..1
(2725 1150);
FORCEPROP 3 LASTPIN (2675 1150) SIG_NAME M_E_CPU0_SB_CA<5>
J 0
(2685 1160);
DISPLAY 0.659574 (2685 1160);
PAINT MONO (2685 1160);
DISPLAY INVISIBLE (2685 1160);
FORCEPROP 1 LASTPIN (2675 1150) BN 5
J 0
(2663 1158);
DISPLAY 0.680851 (2663 1158);
PAINT GREEN (2663 1158);
FORCEPROP 2 LAST CDS_LIB standard
J 0
(2725 1150);
DISPLAY INVISIBLE (2725 1150);
FORCEPROP 1 LAST BODY_TYPE PLUMBING
J 0
(2725 1200);
DISPLAY 0.872340 (2725 1200);
PAINT GREEN (2725 1200);
DISPLAY INVISIBLE (2725 1200);
FORCEPROP 1 LAST HDL_TAP TRUE
J 0
(3050 1025);
DISPLAY 0.872340 (3050 1025);
DISPLAY INVISIBLE (3050 1025);
FORCEPROP 1 LAST PATH I111
J 0
(2723 1150);
DISPLAY 0.872340 (2723 1150);
PAINT GREEN (2723 1150);
DISPLAY INVISIBLE (2723 1150);
FORCEADD TAP..1
(2725 1400);
FORCEPROP 3 LASTPIN (2675 1400) SIG_NAME M_E_CPU0_SA_CA<0>
J 0
(2685 1410);
DISPLAY 0.659574 (2685 1410);
PAINT MONO (2685 1410);
DISPLAY INVISIBLE (2685 1410);
FORCEPROP 1 LASTPIN (2675 1400) BN 0
J 0
(2663 1408);
DISPLAY 0.680851 (2663 1408);
PAINT GREEN (2663 1408);
FORCEPROP 2 LAST CDS_LIB standard
J 0
(2725 1400);
DISPLAY INVISIBLE (2725 1400);
FORCEPROP 1 LAST BODY_TYPE PLUMBING
J 0
(2725 1450);
DISPLAY 0.872340 (2725 1450);
PAINT GREEN (2725 1450);
DISPLAY INVISIBLE (2725 1450);
FORCEPROP 1 LAST HDL_TAP TRUE
J 0
(3050 1275);
DISPLAY 0.872340 (3050 1275);
DISPLAY INVISIBLE (3050 1275);
FORCEPROP 1 LAST PATH I112
J 0
(2723 1400);
DISPLAY 0.872340 (2723 1400);
PAINT GREEN (2723 1400);
DISPLAY INVISIBLE (2723 1400);
FORCEADD TAP..1
(2725 1450);
FORCEPROP 3 LASTPIN (2675 1450) SIG_NAME M_E_CPU0_SA_CA<1>
J 0
(2685 1460);
DISPLAY 0.659574 (2685 1460);
PAINT MONO (2685 1460);
DISPLAY INVISIBLE (2685 1460);
FORCEPROP 1 LASTPIN (2675 1450) BN 1
J 0
(2663 1458);
DISPLAY 0.680851 (2663 1458);
PAINT GREEN (2663 1458);
FORCEPROP 2 LAST CDS_LIB standard
J 0
(2725 1450);
DISPLAY INVISIBLE (2725 1450);
FORCEPROP 1 LAST BODY_TYPE PLUMBING
J 0
(2725 1500);
DISPLAY 0.872340 (2725 1500);
PAINT GREEN (2725 1500);
DISPLAY INVISIBLE (2725 1500);
FORCEPROP 1 LAST HDL_TAP TRUE
J 0
(3050 1325);
DISPLAY 0.872340 (3050 1325);
DISPLAY INVISIBLE (3050 1325);
FORCEPROP 1 LAST PATH I113
J 0
(2723 1450);
DISPLAY 0.872340 (2723 1450);
PAINT GREEN (2723 1450);
DISPLAY INVISIBLE (2723 1450);
FORCEADD TAP..1
(2725 1500);
FORCEPROP 3 LASTPIN (2675 1500) SIG_NAME M_E_CPU0_SA_CA<2>
J 0
(2685 1510);
DISPLAY 0.659574 (2685 1510);
PAINT MONO (2685 1510);
DISPLAY INVISIBLE (2685 1510);
FORCEPROP 1 LASTPIN (2675 1500) BN 2
J 0
(2663 1508);
DISPLAY 0.680851 (2663 1508);
PAINT GREEN (2663 1508);
FORCEPROP 2 LAST CDS_LIB standard
J 0
(2725 1500);
DISPLAY INVISIBLE (2725 1500);
FORCEPROP 1 LAST BODY_TYPE PLUMBING
J 0
(2725 1550);
DISPLAY 0.872340 (2725 1550);
PAINT GREEN (2725 1550);
DISPLAY INVISIBLE (2725 1550);
FORCEPROP 1 LAST HDL_TAP TRUE
J 0
(3050 1375);
DISPLAY 0.872340 (3050 1375);
DISPLAY INVISIBLE (3050 1375);
FORCEPROP 1 LAST PATH I114
J 0
(2723 1500);
DISPLAY 0.872340 (2723 1500);
PAINT GREEN (2723 1500);
DISPLAY INVISIBLE (2723 1500);
FORCEADD TAP..1
(2725 1600);
FORCEPROP 3 LASTPIN (2675 1600) SIG_NAME M_E_CPU0_SA_CA<4>
J 0
(2685 1610);
DISPLAY 0.659574 (2685 1610);
PAINT MONO (2685 1610);
DISPLAY INVISIBLE (2685 1610);
FORCEPROP 1 LASTPIN (2675 1600) BN 4
J 0
(2663 1608);
DISPLAY 0.680851 (2663 1608);
PAINT GREEN (2663 1608);
FORCEPROP 2 LAST CDS_LIB standard
J 0
(2725 1600);
DISPLAY INVISIBLE (2725 1600);
FORCEPROP 1 LAST BODY_TYPE PLUMBING
J 0
(2725 1650);
DISPLAY 0.872340 (2725 1650);
PAINT GREEN (2725 1650);
DISPLAY INVISIBLE (2725 1650);
FORCEPROP 1 LAST HDL_TAP TRUE
J 0
(3050 1475);
DISPLAY 0.872340 (3050 1475);
DISPLAY INVISIBLE (3050 1475);
FORCEPROP 1 LAST PATH I115
J 0
(2723 1600);
DISPLAY 0.872340 (2723 1600);
PAINT GREEN (2723 1600);
DISPLAY INVISIBLE (2723 1600);
FORCEADD TAP..1
(2725 1550);
FORCEPROP 3 LASTPIN (2675 1550) SIG_NAME M_E_CPU0_SA_CA<3>
J 0
(2685 1560);
DISPLAY 0.659574 (2685 1560);
PAINT MONO (2685 1560);
DISPLAY INVISIBLE (2685 1560);
FORCEPROP 1 LASTPIN (2675 1550) BN 3
J 0
(2663 1558);
DISPLAY 0.680851 (2663 1558);
PAINT GREEN (2663 1558);
FORCEPROP 2 LAST CDS_LIB standard
J 0
(2725 1550);
DISPLAY INVISIBLE (2725 1550);
FORCEPROP 1 LAST BODY_TYPE PLUMBING
J 0
(2725 1600);
DISPLAY 0.872340 (2725 1600);
PAINT GREEN (2725 1600);
DISPLAY INVISIBLE (2725 1600);
FORCEPROP 1 LAST HDL_TAP TRUE
J 0
(3050 1425);
DISPLAY 0.872340 (3050 1425);
DISPLAY INVISIBLE (3050 1425);
FORCEPROP 1 LAST PATH I116
J 0
(2723 1550);
DISPLAY 0.872340 (2723 1550);
PAINT GREEN (2723 1550);
DISPLAY INVISIBLE (2723 1550);
FORCEADD TAP..1
(2725 1700);
FORCEPROP 3 LASTPIN (2675 1700) SIG_NAME M_E_CPU0_SA_CA<6>
J 0
(2685 1710);
DISPLAY 0.659574 (2685 1710);
PAINT MONO (2685 1710);
DISPLAY INVISIBLE (2685 1710);
FORCEPROP 1 LASTPIN (2675 1700) BN 6
J 0
(2663 1708);
DISPLAY 0.680851 (2663 1708);
PAINT GREEN (2663 1708);
FORCEPROP 2 LAST CDS_LIB standard
J 0
(2725 1700);
DISPLAY INVISIBLE (2725 1700);
FORCEPROP 1 LAST BODY_TYPE PLUMBING
J 0
(2725 1750);
DISPLAY 0.872340 (2725 1750);
PAINT GREEN (2725 1750);
DISPLAY INVISIBLE (2725 1750);
FORCEPROP 1 LAST HDL_TAP TRUE
J 0
(3050 1575);
DISPLAY 0.872340 (3050 1575);
DISPLAY INVISIBLE (3050 1575);
FORCEPROP 1 LAST PATH I117
J 0
(2723 1700);
DISPLAY 0.872340 (2723 1700);
PAINT GREEN (2723 1700);
DISPLAY INVISIBLE (2723 1700);
FORCEADD TAP..1
(2725 1650);
FORCEPROP 3 LASTPIN (2675 1650) SIG_NAME M_E_CPU0_SA_CA<5>
J 0
(2685 1660);
DISPLAY 0.659574 (2685 1660);
PAINT MONO (2685 1660);
DISPLAY INVISIBLE (2685 1660);
FORCEPROP 1 LASTPIN (2675 1650) BN 5
J 0
(2663 1658);
DISPLAY 0.680851 (2663 1658);
PAINT GREEN (2663 1658);
FORCEPROP 2 LAST CDS_LIB standard
J 0
(2725 1650);
DISPLAY INVISIBLE (2725 1650);
FORCEPROP 1 LAST BODY_TYPE PLUMBING
J 0
(2725 1700);
DISPLAY 0.872340 (2725 1700);
PAINT GREEN (2725 1700);
DISPLAY INVISIBLE (2725 1700);
FORCEPROP 1 LAST HDL_TAP TRUE
J 0
(3050 1525);
DISPLAY 0.872340 (3050 1525);
DISPLAY INVISIBLE (3050 1525);
FORCEPROP 1 LAST PATH I118
J 0
(2723 1650);
DISPLAY 0.872340 (2723 1650);
PAINT GREEN (2723 1650);
DISPLAY INVISIBLE (2723 1650);
FORCEADD TAP..1
(2725 1850);
FORCEPROP 3 LASTPIN (2675 1850) SIG_NAME M_E_CPU0_SB_DQS_DN<0>
J 0
(2685 1860);
DISPLAY 0.659574 (2685 1860);
PAINT MONO (2685 1860);
DISPLAY INVISIBLE (2685 1860);
FORCEPROP 1 LASTPIN (2675 1850) BN 0
J 0
(2663 1858);
DISPLAY 0.680851 (2663 1858);
PAINT GREEN (2663 1858);
FORCEPROP 2 LAST CDS_LIB standard
J 0
(2725 1850);
DISPLAY INVISIBLE (2725 1850);
FORCEPROP 1 LAST BODY_TYPE PLUMBING
J 0
(2725 1900);
DISPLAY 0.872340 (2725 1900);
PAINT GREEN (2725 1900);
DISPLAY INVISIBLE (2725 1900);
FORCEPROP 1 LAST HDL_TAP TRUE
J 0
(3050 1725);
DISPLAY 0.872340 (3050 1725);
DISPLAY INVISIBLE (3050 1725);
FORCEPROP 1 LAST PATH I119
J 0
(2723 1850);
DISPLAY 0.872340 (2723 1850);
PAINT GREEN (2723 1850);
DISPLAY INVISIBLE (2723 1850);
FORCEADD TAP..1
R 2
(-700 200);
FORCEPROP 3 LASTPIN (-650 200) SIG_NAME M_E_CPU0_SB_CB<3>
J 0
(-640 210);
DISPLAY 0.659574 (-640 210);
PAINT MONO (-640 210);
DISPLAY INVISIBLE (-640 210);
FORCEPROP 1 LASTPIN (-650 200) BN 3
J 2
(-638 208);
DISPLAY 0.680851 (-638 208);
PAINT GREEN (-638 208);
FORCEPROP 2 LAST CDS_LIB standard
J 0
(-700 200);
DISPLAY INVISIBLE (-700 200);
FORCEPROP 1 LAST BODY_TYPE PLUMBING
J 2
(-700 250);
DISPLAY 0.872340 (-700 250);
PAINT GREEN (-700 250);
DISPLAY INVISIBLE (-700 250);
FORCEPROP 1 LAST HDL_TAP TRUE
J 2
(-1025 75);
DISPLAY 0.872340 (-1025 75);
DISPLAY INVISIBLE (-1025 75);
FORCEPROP 1 LAST PATH I12
J 2
(-698 200);
DISPLAY 0.872340 (-698 200);
PAINT GREEN (-698 200);
DISPLAY INVISIBLE (-698 200);
FORCEADD TAP..1
(2725 1950);
FORCEPROP 3 LASTPIN (2675 1950) SIG_NAME M_E_CPU0_SB_DQS_DN<2>
J 0
(2685 1960);
DISPLAY 0.659574 (2685 1960);
PAINT MONO (2685 1960);
DISPLAY INVISIBLE (2685 1960);
FORCEPROP 1 LASTPIN (2675 1950) BN 2
J 0
(2663 1958);
DISPLAY 0.680851 (2663 1958);
PAINT GREEN (2663 1958);
FORCEPROP 2 LAST CDS_LIB standard
J 0
(2725 1950);
DISPLAY INVISIBLE (2725 1950);
FORCEPROP 1 LAST BODY_TYPE PLUMBING
J 0
(2725 2000);
DISPLAY 0.872340 (2725 2000);
PAINT GREEN (2725 2000);
DISPLAY INVISIBLE (2725 2000);
FORCEPROP 1 LAST HDL_TAP TRUE
J 0
(3050 1825);
DISPLAY 0.872340 (3050 1825);
DISPLAY INVISIBLE (3050 1825);
FORCEPROP 1 LAST PATH I120
J 0
(2723 1950);
DISPLAY 0.872340 (2723 1950);
PAINT GREEN (2723 1950);
DISPLAY INVISIBLE (2723 1950);
FORCEADD TAP..1
(2725 2000);
FORCEPROP 3 LASTPIN (2675 2000) SIG_NAME M_E_CPU0_SB_DQS_DN<3>
J 0
(2685 2010);
DISPLAY 0.659574 (2685 2010);
PAINT MONO (2685 2010);
DISPLAY INVISIBLE (2685 2010);
FORCEPROP 1 LASTPIN (2675 2000) BN 3
J 0
(2663 2008);
DISPLAY 0.680851 (2663 2008);
PAINT GREEN (2663 2008);
FORCEPROP 2 LAST CDS_LIB standard
J 0
(2725 2000);
DISPLAY INVISIBLE (2725 2000);
FORCEPROP 1 LAST BODY_TYPE PLUMBING
J 0
(2725 2050);
DISPLAY 0.872340 (2725 2050);
PAINT GREEN (2725 2050);
DISPLAY INVISIBLE (2725 2050);
FORCEPROP 1 LAST HDL_TAP TRUE
J 0
(3050 1875);
DISPLAY 0.872340 (3050 1875);
DISPLAY INVISIBLE (3050 1875);
FORCEPROP 1 LAST PATH I121
J 0
(2723 2000);
DISPLAY 0.872340 (2723 2000);
PAINT GREEN (2723 2000);
DISPLAY INVISIBLE (2723 2000);
FORCEADD TAP..1
(2725 1900);
FORCEPROP 3 LASTPIN (2675 1900) SIG_NAME M_E_CPU0_SB_DQS_DN<1>
J 0
(2685 1910);
DISPLAY 0.659574 (2685 1910);
PAINT MONO (2685 1910);
DISPLAY INVISIBLE (2685 1910);
FORCEPROP 1 LASTPIN (2675 1900) BN 1
J 0
(2663 1908);
DISPLAY 0.680851 (2663 1908);
PAINT GREEN (2663 1908);
FORCEPROP 2 LAST CDS_LIB standard
J 0
(2725 1900);
DISPLAY INVISIBLE (2725 1900);
FORCEPROP 1 LAST BODY_TYPE PLUMBING
J 0
(2725 1950);
DISPLAY 0.872340 (2725 1950);
PAINT GREEN (2725 1950);
DISPLAY INVISIBLE (2725 1950);
FORCEPROP 1 LAST HDL_TAP TRUE
J 0
(3050 1775);
DISPLAY 0.872340 (3050 1775);
DISPLAY INVISIBLE (3050 1775);
FORCEPROP 1 LAST PATH I122
J 0
(2723 1900);
DISPLAY 0.872340 (2723 1900);
PAINT GREEN (2723 1900);
DISPLAY INVISIBLE (2723 1900);
FORCEADD TAP..1
(2725 2100);
FORCEPROP 3 LASTPIN (2675 2100) SIG_NAME M_E_CPU0_SB_DQS_DN<5>
J 0
(2685 2110);
DISPLAY 0.659574 (2685 2110);
PAINT MONO (2685 2110);
DISPLAY INVISIBLE (2685 2110);
FORCEPROP 1 LASTPIN (2675 2100) BN 5
J 0
(2663 2108);
DISPLAY 0.680851 (2663 2108);
PAINT GREEN (2663 2108);
FORCEPROP 2 LAST CDS_LIB standard
J 0
(2725 2100);
DISPLAY INVISIBLE (2725 2100);
FORCEPROP 1 LAST BODY_TYPE PLUMBING
J 0
(2725 2150);
DISPLAY 0.872340 (2725 2150);
PAINT GREEN (2725 2150);
DISPLAY INVISIBLE (2725 2150);
FORCEPROP 1 LAST HDL_TAP TRUE
J 0
(3050 1975);
DISPLAY 0.872340 (3050 1975);
DISPLAY INVISIBLE (3050 1975);
FORCEPROP 1 LAST PATH I123
J 0
(2723 2100);
DISPLAY 0.872340 (2723 2100);
PAINT GREEN (2723 2100);
DISPLAY INVISIBLE (2723 2100);
FORCEADD TAP..1
(2725 2050);
FORCEPROP 3 LASTPIN (2675 2050) SIG_NAME M_E_CPU0_SB_DQS_DN<4>
J 0
(2685 2060);
DISPLAY 0.659574 (2685 2060);
PAINT MONO (2685 2060);
DISPLAY INVISIBLE (2685 2060);
FORCEPROP 1 LASTPIN (2675 2050) BN 4
J 0
(2663 2058);
DISPLAY 0.680851 (2663 2058);
PAINT GREEN (2663 2058);
FORCEPROP 2 LAST CDS_LIB standard
J 0
(2725 2050);
DISPLAY INVISIBLE (2725 2050);
FORCEPROP 1 LAST BODY_TYPE PLUMBING
J 0
(2725 2100);
DISPLAY 0.872340 (2725 2100);
PAINT GREEN (2725 2100);
DISPLAY INVISIBLE (2725 2100);
FORCEPROP 1 LAST HDL_TAP TRUE
J 0
(3050 1925);
DISPLAY 0.872340 (3050 1925);
DISPLAY INVISIBLE (3050 1925);
FORCEPROP 1 LAST PATH I124
J 0
(2723 2050);
DISPLAY 0.872340 (2723 2050);
PAINT GREEN (2723 2050);
DISPLAY INVISIBLE (2723 2050);
FORCEADD TAP..1
(2725 2200);
FORCEPROP 3 LASTPIN (2675 2200) SIG_NAME M_E_CPU0_SB_DQS_DN<7>
J 0
(2685 2210);
DISPLAY 0.659574 (2685 2210);
PAINT MONO (2685 2210);
DISPLAY INVISIBLE (2685 2210);
FORCEPROP 1 LASTPIN (2675 2200) BN 7
J 0
(2663 2208);
DISPLAY 0.680851 (2663 2208);
PAINT GREEN (2663 2208);
FORCEPROP 2 LAST CDS_LIB standard
J 0
(2725 2200);
DISPLAY INVISIBLE (2725 2200);
FORCEPROP 1 LAST BODY_TYPE PLUMBING
J 0
(2725 2250);
DISPLAY 0.872340 (2725 2250);
PAINT GREEN (2725 2250);
DISPLAY INVISIBLE (2725 2250);
FORCEPROP 1 LAST HDL_TAP TRUE
J 0
(3050 2075);
DISPLAY 0.872340 (3050 2075);
DISPLAY INVISIBLE (3050 2075);
FORCEPROP 1 LAST PATH I125
J 0
(2723 2200);
DISPLAY 0.872340 (2723 2200);
PAINT GREEN (2723 2200);
DISPLAY INVISIBLE (2723 2200);
FORCEADD TAP..1
(2725 2250);
FORCEPROP 3 LASTPIN (2675 2250) SIG_NAME M_E_CPU0_SB_DQS_DN<8>
J 0
(2685 2260);
DISPLAY 0.659574 (2685 2260);
PAINT MONO (2685 2260);
DISPLAY INVISIBLE (2685 2260);
FORCEPROP 1 LASTPIN (2675 2250) BN 8
J 0
(2663 2258);
DISPLAY 0.680851 (2663 2258);
PAINT GREEN (2663 2258);
FORCEPROP 2 LAST CDS_LIB standard
J 0
(2725 2250);
DISPLAY INVISIBLE (2725 2250);
FORCEPROP 1 LAST BODY_TYPE PLUMBING
J 0
(2725 2300);
DISPLAY 0.872340 (2725 2300);
PAINT GREEN (2725 2300);
DISPLAY INVISIBLE (2725 2300);
FORCEPROP 1 LAST HDL_TAP TRUE
J 0
(3050 2125);
DISPLAY 0.872340 (3050 2125);
DISPLAY INVISIBLE (3050 2125);
FORCEPROP 1 LAST PATH I126
J 0
(2723 2250);
DISPLAY 0.872340 (2723 2250);
PAINT GREEN (2723 2250);
DISPLAY INVISIBLE (2723 2250);
FORCEADD TAP..1
(2725 2150);
FORCEPROP 3 LASTPIN (2675 2150) SIG_NAME M_E_CPU0_SB_DQS_DN<6>
J 0
(2685 2160);
DISPLAY 0.659574 (2685 2160);
PAINT MONO (2685 2160);
DISPLAY INVISIBLE (2685 2160);
FORCEPROP 1 LASTPIN (2675 2150) BN 6
J 0
(2663 2158);
DISPLAY 0.680851 (2663 2158);
PAINT GREEN (2663 2158);
FORCEPROP 2 LAST CDS_LIB standard
J 0
(2725 2150);
DISPLAY INVISIBLE (2725 2150);
FORCEPROP 1 LAST BODY_TYPE PLUMBING
J 0
(2725 2200);
DISPLAY 0.872340 (2725 2200);
PAINT GREEN (2725 2200);
DISPLAY INVISIBLE (2725 2200);
FORCEPROP 1 LAST HDL_TAP TRUE
J 0
(3050 2025);
DISPLAY 0.872340 (3050 2025);
DISPLAY INVISIBLE (3050 2025);
FORCEPROP 1 LAST PATH I127
J 0
(2723 2150);
DISPLAY 0.872340 (2723 2150);
PAINT GREEN (2723 2150);
DISPLAY INVISIBLE (2723 2150);
FORCEADD TAP..1
(2725 2400);
FORCEPROP 3 LASTPIN (2675 2400) SIG_NAME M_E_CPU0_SB_DQS_DP<0>
J 0
(2685 2410);
DISPLAY 0.659574 (2685 2410);
PAINT MONO (2685 2410);
DISPLAY INVISIBLE (2685 2410);
FORCEPROP 1 LASTPIN (2675 2400) BN 0
J 0
(2663 2408);
DISPLAY 0.680851 (2663 2408);
PAINT GREEN (2663 2408);
FORCEPROP 2 LAST CDS_LIB standard
J 0
(2725 2400);
DISPLAY INVISIBLE (2725 2400);
FORCEPROP 1 LAST BODY_TYPE PLUMBING
J 0
(2725 2450);
DISPLAY 0.872340 (2725 2450);
PAINT GREEN (2725 2450);
DISPLAY INVISIBLE (2725 2450);
FORCEPROP 1 LAST HDL_TAP TRUE
J 0
(3050 2275);
DISPLAY 0.872340 (3050 2275);
DISPLAY INVISIBLE (3050 2275);
FORCEPROP 1 LAST PATH I128
J 0
(2723 2400);
DISPLAY 0.872340 (2723 2400);
PAINT GREEN (2723 2400);
DISPLAY INVISIBLE (2723 2400);
FORCEADD TAP..1
(2725 2300);
FORCEPROP 3 LASTPIN (2675 2300) SIG_NAME M_E_CPU0_SB_DQS_DN<9>
J 0
(2685 2310);
DISPLAY 0.659574 (2685 2310);
PAINT MONO (2685 2310);
DISPLAY INVISIBLE (2685 2310);
FORCEPROP 1 LASTPIN (2675 2300) BN 9
J 0
(2663 2308);
DISPLAY 0.680851 (2663 2308);
PAINT GREEN (2663 2308);
FORCEPROP 2 LAST CDS_LIB standard
J 0
(2725 2300);
DISPLAY INVISIBLE (2725 2300);
FORCEPROP 1 LAST BODY_TYPE PLUMBING
J 0
(2725 2350);
DISPLAY 0.872340 (2725 2350);
PAINT GREEN (2725 2350);
DISPLAY INVISIBLE (2725 2350);
FORCEPROP 1 LAST HDL_TAP TRUE
J 0
(3050 2175);
DISPLAY 0.872340 (3050 2175);
DISPLAY INVISIBLE (3050 2175);
FORCEPROP 1 LAST PATH I129
J 0
(2723 2300);
DISPLAY 0.872340 (2723 2300);
PAINT GREEN (2723 2300);
DISPLAY INVISIBLE (2723 2300);
FORCEADD TAP..1
R 2
(-700 250);
FORCEPROP 3 LASTPIN (-650 250) SIG_NAME M_E_CPU0_SB_CB<4>
J 0
(-640 260);
DISPLAY 0.659574 (-640 260);
PAINT MONO (-640 260);
DISPLAY INVISIBLE (-640 260);
FORCEPROP 1 LASTPIN (-650 250) BN 4
J 2
(-638 258);
DISPLAY 0.680851 (-638 258);
PAINT GREEN (-638 258);
FORCEPROP 2 LAST CDS_LIB standard
J 0
(-700 250);
DISPLAY INVISIBLE (-700 250);
FORCEPROP 1 LAST BODY_TYPE PLUMBING
J 2
(-700 300);
DISPLAY 0.872340 (-700 300);
PAINT GREEN (-700 300);
DISPLAY INVISIBLE (-700 300);
FORCEPROP 1 LAST HDL_TAP TRUE
J 2
(-1025 125);
DISPLAY 0.872340 (-1025 125);
DISPLAY INVISIBLE (-1025 125);
FORCEPROP 1 LAST PATH I13
J 2
(-698 250);
DISPLAY 0.872340 (-698 250);
PAINT GREEN (-698 250);
DISPLAY INVISIBLE (-698 250);
FORCEADD TAP..1
(2725 2450);
FORCEPROP 3 LASTPIN (2675 2450) SIG_NAME M_E_CPU0_SB_DQS_DP<1>
J 0
(2685 2460);
DISPLAY 0.659574 (2685 2460);
PAINT MONO (2685 2460);
DISPLAY INVISIBLE (2685 2460);
FORCEPROP 1 LASTPIN (2675 2450) BN 1
J 0
(2663 2458);
DISPLAY 0.680851 (2663 2458);
PAINT GREEN (2663 2458);
FORCEPROP 2 LAST CDS_LIB standard
J 0
(2725 2450);
DISPLAY INVISIBLE (2725 2450);
FORCEPROP 1 LAST BODY_TYPE PLUMBING
J 0
(2725 2500);
DISPLAY 0.872340 (2725 2500);
PAINT GREEN (2725 2500);
DISPLAY INVISIBLE (2725 2500);
FORCEPROP 1 LAST HDL_TAP TRUE
J 0
(3050 2325);
DISPLAY 0.872340 (3050 2325);
DISPLAY INVISIBLE (3050 2325);
FORCEPROP 1 LAST PATH I130
J 0
(2723 2450);
DISPLAY 0.872340 (2723 2450);
PAINT GREEN (2723 2450);
DISPLAY INVISIBLE (2723 2450);
FORCEADD TAP..1
(2725 2500);
FORCEPROP 3 LASTPIN (2675 2500) SIG_NAME M_E_CPU0_SB_DQS_DP<2>
J 0
(2685 2510);
DISPLAY 0.659574 (2685 2510);
PAINT MONO (2685 2510);
DISPLAY INVISIBLE (2685 2510);
FORCEPROP 1 LASTPIN (2675 2500) BN 2
J 0
(2663 2508);
DISPLAY 0.680851 (2663 2508);
PAINT GREEN (2663 2508);
FORCEPROP 2 LAST CDS_LIB standard
J 0
(2725 2500);
DISPLAY INVISIBLE (2725 2500);
FORCEPROP 1 LAST BODY_TYPE PLUMBING
J 0
(2725 2550);
DISPLAY 0.872340 (2725 2550);
PAINT GREEN (2725 2550);
DISPLAY INVISIBLE (2725 2550);
FORCEPROP 1 LAST HDL_TAP TRUE
J 0
(3050 2375);
DISPLAY 0.872340 (3050 2375);
DISPLAY INVISIBLE (3050 2375);
FORCEPROP 1 LAST PATH I131
J 0
(2723 2500);
DISPLAY 0.872340 (2723 2500);
PAINT GREEN (2723 2500);
DISPLAY INVISIBLE (2723 2500);
FORCEADD TAP..1
(2725 2600);
FORCEPROP 3 LASTPIN (2675 2600) SIG_NAME M_E_CPU0_SB_DQS_DP<4>
J 0
(2685 2610);
DISPLAY 0.659574 (2685 2610);
PAINT MONO (2685 2610);
DISPLAY INVISIBLE (2685 2610);
FORCEPROP 1 LASTPIN (2675 2600) BN 4
J 0
(2663 2608);
DISPLAY 0.680851 (2663 2608);
PAINT GREEN (2663 2608);
FORCEPROP 2 LAST CDS_LIB standard
J 0
(2725 2600);
DISPLAY INVISIBLE (2725 2600);
FORCEPROP 1 LAST BODY_TYPE PLUMBING
J 0
(2725 2650);
DISPLAY 0.872340 (2725 2650);
PAINT GREEN (2725 2650);
DISPLAY INVISIBLE (2725 2650);
FORCEPROP 1 LAST HDL_TAP TRUE
J 0
(3050 2475);
DISPLAY 0.872340 (3050 2475);
DISPLAY INVISIBLE (3050 2475);
FORCEPROP 1 LAST PATH I132
J 0
(2723 2600);
DISPLAY 0.872340 (2723 2600);
PAINT GREEN (2723 2600);
DISPLAY INVISIBLE (2723 2600);
FORCEADD TAP..1
(2725 2650);
FORCEPROP 3 LASTPIN (2675 2650) SIG_NAME M_E_CPU0_SB_DQS_DP<5>
J 0
(2685 2660);
DISPLAY 0.659574 (2685 2660);
PAINT MONO (2685 2660);
DISPLAY INVISIBLE (2685 2660);
FORCEPROP 1 LASTPIN (2675 2650) BN 5
J 0
(2663 2658);
DISPLAY 0.680851 (2663 2658);
PAINT GREEN (2663 2658);
FORCEPROP 2 LAST CDS_LIB standard
J 0
(2725 2650);
DISPLAY INVISIBLE (2725 2650);
FORCEPROP 1 LAST BODY_TYPE PLUMBING
J 0
(2725 2700);
DISPLAY 0.872340 (2725 2700);
PAINT GREEN (2725 2700);
DISPLAY INVISIBLE (2725 2700);
FORCEPROP 1 LAST HDL_TAP TRUE
J 0
(3050 2525);
DISPLAY 0.872340 (3050 2525);
DISPLAY INVISIBLE (3050 2525);
FORCEPROP 1 LAST PATH I133
J 0
(2723 2650);
DISPLAY 0.872340 (2723 2650);
PAINT GREEN (2723 2650);
DISPLAY INVISIBLE (2723 2650);
FORCEADD TAP..1
(2725 2550);
FORCEPROP 3 LASTPIN (2675 2550) SIG_NAME M_E_CPU0_SB_DQS_DP<3>
J 0
(2685 2560);
DISPLAY 0.659574 (2685 2560);
PAINT MONO (2685 2560);
DISPLAY INVISIBLE (2685 2560);
FORCEPROP 1 LASTPIN (2675 2550) BN 3
J 0
(2663 2558);
DISPLAY 0.680851 (2663 2558);
PAINT GREEN (2663 2558);
FORCEPROP 2 LAST CDS_LIB standard
J 0
(2725 2550);
DISPLAY INVISIBLE (2725 2550);
FORCEPROP 1 LAST BODY_TYPE PLUMBING
J 0
(2725 2600);
DISPLAY 0.872340 (2725 2600);
PAINT GREEN (2725 2600);
DISPLAY INVISIBLE (2725 2600);
FORCEPROP 1 LAST HDL_TAP TRUE
J 0
(3050 2425);
DISPLAY 0.872340 (3050 2425);
DISPLAY INVISIBLE (3050 2425);
FORCEPROP 1 LAST PATH I134
J 0
(2723 2550);
DISPLAY 0.872340 (2723 2550);
PAINT GREEN (2723 2550);
DISPLAY INVISIBLE (2723 2550);
FORCEADD TAP..1
(2725 2700);
FORCEPROP 3 LASTPIN (2675 2700) SIG_NAME M_E_CPU0_SB_DQS_DP<6>
J 0
(2685 2710);
DISPLAY 0.659574 (2685 2710);
PAINT MONO (2685 2710);
DISPLAY INVISIBLE (2685 2710);
FORCEPROP 1 LASTPIN (2675 2700) BN 6
J 0
(2663 2708);
DISPLAY 0.680851 (2663 2708);
PAINT GREEN (2663 2708);
FORCEPROP 2 LAST CDS_LIB standard
J 0
(2725 2700);
DISPLAY INVISIBLE (2725 2700);
FORCEPROP 1 LAST BODY_TYPE PLUMBING
J 0
(2725 2750);
DISPLAY 0.872340 (2725 2750);
PAINT GREEN (2725 2750);
DISPLAY INVISIBLE (2725 2750);
FORCEPROP 1 LAST HDL_TAP TRUE
J 0
(3050 2575);
DISPLAY 0.872340 (3050 2575);
DISPLAY INVISIBLE (3050 2575);
FORCEPROP 1 LAST PATH I135
J 0
(2723 2700);
DISPLAY 0.872340 (2723 2700);
PAINT GREEN (2723 2700);
DISPLAY INVISIBLE (2723 2700);
FORCEADD TAP..1
(2725 2750);
FORCEPROP 3 LASTPIN (2675 2750) SIG_NAME M_E_CPU0_SB_DQS_DP<7>
J 0
(2685 2760);
DISPLAY 0.659574 (2685 2760);
PAINT MONO (2685 2760);
DISPLAY INVISIBLE (2685 2760);
FORCEPROP 1 LASTPIN (2675 2750) BN 7
J 0
(2663 2758);
DISPLAY 0.680851 (2663 2758);
PAINT GREEN (2663 2758);
FORCEPROP 2 LAST CDS_LIB standard
J 0
(2725 2750);
DISPLAY INVISIBLE (2725 2750);
FORCEPROP 1 LAST BODY_TYPE PLUMBING
J 0
(2725 2800);
DISPLAY 0.872340 (2725 2800);
PAINT GREEN (2725 2800);
DISPLAY INVISIBLE (2725 2800);
FORCEPROP 1 LAST HDL_TAP TRUE
J 0
(3050 2625);
DISPLAY 0.872340 (3050 2625);
DISPLAY INVISIBLE (3050 2625);
FORCEPROP 1 LAST PATH I136
J 0
(2723 2750);
DISPLAY 0.872340 (2723 2750);
PAINT GREEN (2723 2750);
DISPLAY INVISIBLE (2723 2750);
FORCEADD TAP..1
(2725 2850);
FORCEPROP 3 LASTPIN (2675 2850) SIG_NAME M_E_CPU0_SB_DQS_DP<9>
J 0
(2685 2860);
DISPLAY 0.659574 (2685 2860);
PAINT MONO (2685 2860);
DISPLAY INVISIBLE (2685 2860);
FORCEPROP 1 LASTPIN (2675 2850) BN 9
J 0
(2663 2858);
DISPLAY 0.680851 (2663 2858);
PAINT GREEN (2663 2858);
FORCEPROP 2 LAST CDS_LIB standard
J 0
(2725 2850);
DISPLAY INVISIBLE (2725 2850);
FORCEPROP 1 LAST BODY_TYPE PLUMBING
J 0
(2725 2900);
DISPLAY 0.872340 (2725 2900);
PAINT GREEN (2725 2900);
DISPLAY INVISIBLE (2725 2900);
FORCEPROP 1 LAST HDL_TAP TRUE
J 0
(3050 2725);
DISPLAY 0.872340 (3050 2725);
DISPLAY INVISIBLE (3050 2725);
FORCEPROP 1 LAST PATH I137
J 0
(2723 2850);
DISPLAY 0.872340 (2723 2850);
PAINT GREEN (2723 2850);
DISPLAY INVISIBLE (2723 2850);
FORCEADD TAP..1
(2725 2800);
FORCEPROP 3 LASTPIN (2675 2800) SIG_NAME M_E_CPU0_SB_DQS_DP<8>
J 0
(2685 2810);
DISPLAY 0.659574 (2685 2810);
PAINT MONO (2685 2810);
DISPLAY INVISIBLE (2685 2810);
FORCEPROP 1 LASTPIN (2675 2800) BN 8
J 0
(2663 2808);
DISPLAY 0.680851 (2663 2808);
PAINT GREEN (2663 2808);
FORCEPROP 2 LAST CDS_LIB standard
J 0
(2725 2800);
DISPLAY INVISIBLE (2725 2800);
FORCEPROP 1 LAST BODY_TYPE PLUMBING
J 0
(2725 2850);
DISPLAY 0.872340 (2725 2850);
PAINT GREEN (2725 2850);
DISPLAY INVISIBLE (2725 2850);
FORCEPROP 1 LAST HDL_TAP TRUE
J 0
(3050 2675);
DISPLAY 0.872340 (3050 2675);
DISPLAY INVISIBLE (3050 2675);
FORCEPROP 1 LAST PATH I138
J 0
(2723 2800);
DISPLAY 0.872340 (2723 2800);
PAINT GREEN (2723 2800);
DISPLAY INVISIBLE (2723 2800);
FORCEADD TAP..1
(2725 3000);
FORCEPROP 3 LASTPIN (2675 3000) SIG_NAME M_E_CPU0_SA_DQS_DN<0>
J 0
(2685 3010);
DISPLAY 0.659574 (2685 3010);
PAINT MONO (2685 3010);
DISPLAY INVISIBLE (2685 3010);
FORCEPROP 1 LASTPIN (2675 3000) BN 0
J 0
(2663 3008);
DISPLAY 0.680851 (2663 3008);
PAINT GREEN (2663 3008);
FORCEPROP 2 LAST CDS_LIB standard
J 0
(2725 3000);
DISPLAY INVISIBLE (2725 3000);
FORCEPROP 1 LAST BODY_TYPE PLUMBING
J 0
(2725 3050);
DISPLAY 0.872340 (2725 3050);
PAINT GREEN (2725 3050);
DISPLAY INVISIBLE (2725 3050);
FORCEPROP 1 LAST HDL_TAP TRUE
J 0
(3050 2875);
DISPLAY 0.872340 (3050 2875);
DISPLAY INVISIBLE (3050 2875);
FORCEPROP 1 LAST PATH I139
J 0
(2723 3000);
DISPLAY 0.872340 (2723 3000);
PAINT GREEN (2723 3000);
DISPLAY INVISIBLE (2723 3000);
FORCEADD TAP..1
R 2
(-700 300);
FORCEPROP 3 LASTPIN (-650 300) SIG_NAME M_E_CPU0_SB_CB<5>
J 0
(-640 310);
DISPLAY 0.659574 (-640 310);
PAINT MONO (-640 310);
DISPLAY INVISIBLE (-640 310);
FORCEPROP 1 LASTPIN (-650 300) BN 5
J 2
(-638 308);
DISPLAY 0.680851 (-638 308);
PAINT GREEN (-638 308);
FORCEPROP 2 LAST CDS_LIB standard
J 0
(-700 300);
DISPLAY INVISIBLE (-700 300);
FORCEPROP 1 LAST BODY_TYPE PLUMBING
J 2
(-700 350);
DISPLAY 0.872340 (-700 350);
PAINT GREEN (-700 350);
DISPLAY INVISIBLE (-700 350);
FORCEPROP 1 LAST HDL_TAP TRUE
J 2
(-1025 175);
DISPLAY 0.872340 (-1025 175);
DISPLAY INVISIBLE (-1025 175);
FORCEPROP 1 LAST PATH I14
J 2
(-698 300);
DISPLAY 0.872340 (-698 300);
PAINT GREEN (-698 300);
DISPLAY INVISIBLE (-698 300);
FORCEADD TAP..1
(2725 3100);
FORCEPROP 3 LASTPIN (2675 3100) SIG_NAME M_E_CPU0_SA_DQS_DN<2>
J 0
(2685 3110);
DISPLAY 0.659574 (2685 3110);
PAINT MONO (2685 3110);
DISPLAY INVISIBLE (2685 3110);
FORCEPROP 1 LASTPIN (2675 3100) BN 2
J 0
(2663 3108);
DISPLAY 0.680851 (2663 3108);
PAINT GREEN (2663 3108);
FORCEPROP 2 LAST CDS_LIB standard
J 0
(2725 3100);
DISPLAY INVISIBLE (2725 3100);
FORCEPROP 1 LAST BODY_TYPE PLUMBING
J 0
(2725 3150);
DISPLAY 0.872340 (2725 3150);
PAINT GREEN (2725 3150);
DISPLAY INVISIBLE (2725 3150);
FORCEPROP 1 LAST HDL_TAP TRUE
J 0
(3050 2975);
DISPLAY 0.872340 (3050 2975);
DISPLAY INVISIBLE (3050 2975);
FORCEPROP 1 LAST PATH I140
J 0
(2723 3100);
DISPLAY 0.872340 (2723 3100);
PAINT GREEN (2723 3100);
DISPLAY INVISIBLE (2723 3100);
FORCEADD TAP..1
(2725 3150);
FORCEPROP 3 LASTPIN (2675 3150) SIG_NAME M_E_CPU0_SA_DQS_DN<3>
J 0
(2685 3160);
DISPLAY 0.659574 (2685 3160);
PAINT MONO (2685 3160);
DISPLAY INVISIBLE (2685 3160);
FORCEPROP 1 LASTPIN (2675 3150) BN 3
J 0
(2663 3158);
DISPLAY 0.680851 (2663 3158);
PAINT GREEN (2663 3158);
FORCEPROP 2 LAST CDS_LIB standard
J 0
(2725 3150);
DISPLAY INVISIBLE (2725 3150);
FORCEPROP 1 LAST BODY_TYPE PLUMBING
J 0
(2725 3200);
DISPLAY 0.872340 (2725 3200);
PAINT GREEN (2725 3200);
DISPLAY INVISIBLE (2725 3200);
FORCEPROP 1 LAST HDL_TAP TRUE
J 0
(3050 3025);
DISPLAY 0.872340 (3050 3025);
DISPLAY INVISIBLE (3050 3025);
FORCEPROP 1 LAST PATH I141
J 0
(2723 3150);
DISPLAY 0.872340 (2723 3150);
PAINT GREEN (2723 3150);
DISPLAY INVISIBLE (2723 3150);
FORCEADD TAP..1
(2725 3050);
FORCEPROP 3 LASTPIN (2675 3050) SIG_NAME M_E_CPU0_SA_DQS_DN<1>
J 0
(2685 3060);
DISPLAY 0.659574 (2685 3060);
PAINT MONO (2685 3060);
DISPLAY INVISIBLE (2685 3060);
FORCEPROP 1 LASTPIN (2675 3050) BN 1
J 0
(2663 3058);
DISPLAY 0.680851 (2663 3058);
PAINT GREEN (2663 3058);
FORCEPROP 2 LAST CDS_LIB standard
J 0
(2725 3050);
DISPLAY INVISIBLE (2725 3050);
FORCEPROP 1 LAST BODY_TYPE PLUMBING
J 0
(2725 3100);
DISPLAY 0.872340 (2725 3100);
PAINT GREEN (2725 3100);
DISPLAY INVISIBLE (2725 3100);
FORCEPROP 1 LAST HDL_TAP TRUE
J 0
(3050 2925);
DISPLAY 0.872340 (3050 2925);
DISPLAY INVISIBLE (3050 2925);
FORCEPROP 1 LAST PATH I142
J 0
(2723 3050);
DISPLAY 0.872340 (2723 3050);
PAINT GREEN (2723 3050);
DISPLAY INVISIBLE (2723 3050);
FORCEADD TAP..1
(2725 3200);
FORCEPROP 3 LASTPIN (2675 3200) SIG_NAME M_E_CPU0_SA_DQS_DN<4>
J 0
(2685 3210);
DISPLAY 0.659574 (2685 3210);
PAINT MONO (2685 3210);
DISPLAY INVISIBLE (2685 3210);
FORCEPROP 1 LASTPIN (2675 3200) BN 4
J 0
(2663 3208);
DISPLAY 0.680851 (2663 3208);
PAINT GREEN (2663 3208);
FORCEPROP 2 LAST CDS_LIB standard
J 0
(2725 3200);
DISPLAY INVISIBLE (2725 3200);
FORCEPROP 1 LAST BODY_TYPE PLUMBING
J 0
(2725 3250);
DISPLAY 0.872340 (2725 3250);
PAINT GREEN (2725 3250);
DISPLAY INVISIBLE (2725 3250);
FORCEPROP 1 LAST HDL_TAP TRUE
J 0
(3050 3075);
DISPLAY 0.872340 (3050 3075);
DISPLAY INVISIBLE (3050 3075);
FORCEPROP 1 LAST PATH I143
J 0
(2723 3200);
DISPLAY 0.872340 (2723 3200);
PAINT GREEN (2723 3200);
DISPLAY INVISIBLE (2723 3200);
FORCEADD TAP..1
(2725 3250);
FORCEPROP 3 LASTPIN (2675 3250) SIG_NAME M_E_CPU0_SA_DQS_DN<5>
J 0
(2685 3260);
DISPLAY 0.659574 (2685 3260);
PAINT MONO (2685 3260);
DISPLAY INVISIBLE (2685 3260);
FORCEPROP 1 LASTPIN (2675 3250) BN 5
J 0
(2663 3258);
DISPLAY 0.680851 (2663 3258);
PAINT GREEN (2663 3258);
FORCEPROP 2 LAST CDS_LIB standard
J 0
(2725 3250);
DISPLAY INVISIBLE (2725 3250);
FORCEPROP 1 LAST BODY_TYPE PLUMBING
J 0
(2725 3300);
DISPLAY 0.872340 (2725 3300);
PAINT GREEN (2725 3300);
DISPLAY INVISIBLE (2725 3300);
FORCEPROP 1 LAST HDL_TAP TRUE
J 0
(3050 3125);
DISPLAY 0.872340 (3050 3125);
DISPLAY INVISIBLE (3050 3125);
FORCEPROP 1 LAST PATH I144
J 0
(2723 3250);
DISPLAY 0.872340 (2723 3250);
PAINT GREEN (2723 3250);
DISPLAY INVISIBLE (2723 3250);
FORCEADD TAP..1
(2725 3300);
FORCEPROP 3 LASTPIN (2675 3300) SIG_NAME M_E_CPU0_SA_DQS_DN<6>
J 0
(2685 3310);
DISPLAY 0.659574 (2685 3310);
PAINT MONO (2685 3310);
DISPLAY INVISIBLE (2685 3310);
FORCEPROP 1 LASTPIN (2675 3300) BN 6
J 0
(2663 3308);
DISPLAY 0.680851 (2663 3308);
PAINT GREEN (2663 3308);
FORCEPROP 2 LAST CDS_LIB standard
J 0
(2725 3300);
DISPLAY INVISIBLE (2725 3300);
FORCEPROP 1 LAST BODY_TYPE PLUMBING
J 0
(2725 3350);
DISPLAY 0.872340 (2725 3350);
PAINT GREEN (2725 3350);
DISPLAY INVISIBLE (2725 3350);
FORCEPROP 1 LAST HDL_TAP TRUE
J 0
(3050 3175);
DISPLAY 0.872340 (3050 3175);
DISPLAY INVISIBLE (3050 3175);
FORCEPROP 1 LAST PATH I145
J 0
(2723 3300);
DISPLAY 0.872340 (2723 3300);
PAINT GREEN (2723 3300);
DISPLAY INVISIBLE (2723 3300);
FORCEADD TAP..1
(2725 3400);
FORCEPROP 3 LASTPIN (2675 3400) SIG_NAME M_E_CPU0_SA_DQS_DN<8>
J 0
(2685 3410);
DISPLAY 0.659574 (2685 3410);
PAINT MONO (2685 3410);
DISPLAY INVISIBLE (2685 3410);
FORCEPROP 1 LASTPIN (2675 3400) BN 8
J 0
(2663 3408);
DISPLAY 0.680851 (2663 3408);
PAINT GREEN (2663 3408);
FORCEPROP 2 LAST CDS_LIB standard
J 0
(2725 3400);
DISPLAY INVISIBLE (2725 3400);
FORCEPROP 1 LAST BODY_TYPE PLUMBING
J 0
(2725 3450);
DISPLAY 0.872340 (2725 3450);
PAINT GREEN (2725 3450);
DISPLAY INVISIBLE (2725 3450);
FORCEPROP 1 LAST HDL_TAP TRUE
J 0
(3050 3275);
DISPLAY 0.872340 (3050 3275);
DISPLAY INVISIBLE (3050 3275);
FORCEPROP 1 LAST PATH I146
J 0
(2723 3400);
DISPLAY 0.872340 (2723 3400);
PAINT GREEN (2723 3400);
DISPLAY INVISIBLE (2723 3400);
FORCEADD TAP..1
(2725 3350);
FORCEPROP 3 LASTPIN (2675 3350) SIG_NAME M_E_CPU0_SA_DQS_DN<7>
J 0
(2685 3360);
DISPLAY 0.659574 (2685 3360);
PAINT MONO (2685 3360);
DISPLAY INVISIBLE (2685 3360);
FORCEPROP 1 LASTPIN (2675 3350) BN 7
J 0
(2663 3358);
DISPLAY 0.680851 (2663 3358);
PAINT GREEN (2663 3358);
FORCEPROP 2 LAST CDS_LIB standard
J 0
(2725 3350);
DISPLAY INVISIBLE (2725 3350);
FORCEPROP 1 LAST BODY_TYPE PLUMBING
J 0
(2725 3400);
DISPLAY 0.872340 (2725 3400);
PAINT GREEN (2725 3400);
DISPLAY INVISIBLE (2725 3400);
FORCEPROP 1 LAST HDL_TAP TRUE
J 0
(3050 3225);
DISPLAY 0.872340 (3050 3225);
DISPLAY INVISIBLE (3050 3225);
FORCEPROP 1 LAST PATH I147
J 0
(2723 3350);
DISPLAY 0.872340 (2723 3350);
PAINT GREEN (2723 3350);
DISPLAY INVISIBLE (2723 3350);
FORCEADD TAP..1
(2725 3550);
FORCEPROP 3 LASTPIN (2675 3550) SIG_NAME M_E_CPU0_SA_DQS_DP<0>
J 0
(2685 3560);
DISPLAY 0.659574 (2685 3560);
PAINT MONO (2685 3560);
DISPLAY INVISIBLE (2685 3560);
FORCEPROP 1 LASTPIN (2675 3550) BN 0
J 0
(2663 3558);
DISPLAY 0.680851 (2663 3558);
PAINT GREEN (2663 3558);
FORCEPROP 2 LAST CDS_LIB standard
J 0
(2725 3550);
DISPLAY INVISIBLE (2725 3550);
FORCEPROP 1 LAST BODY_TYPE PLUMBING
J 0
(2725 3600);
DISPLAY 0.872340 (2725 3600);
PAINT GREEN (2725 3600);
DISPLAY INVISIBLE (2725 3600);
FORCEPROP 1 LAST HDL_TAP TRUE
J 0
(3050 3425);
DISPLAY 0.872340 (3050 3425);
DISPLAY INVISIBLE (3050 3425);
FORCEPROP 1 LAST PATH I148
J 0
(2723 3550);
DISPLAY 0.872340 (2723 3550);
PAINT GREEN (2723 3550);
DISPLAY INVISIBLE (2723 3550);
FORCEADD TAP..1
(2725 3450);
FORCEPROP 3 LASTPIN (2675 3450) SIG_NAME M_E_CPU0_SA_DQS_DN<9>
J 0
(2685 3460);
DISPLAY 0.659574 (2685 3460);
PAINT MONO (2685 3460);
DISPLAY INVISIBLE (2685 3460);
FORCEPROP 1 LASTPIN (2675 3450) BN 9
J 0
(2663 3458);
DISPLAY 0.680851 (2663 3458);
PAINT GREEN (2663 3458);
FORCEPROP 2 LAST CDS_LIB standard
J 0
(2725 3450);
DISPLAY INVISIBLE (2725 3450);
FORCEPROP 1 LAST BODY_TYPE PLUMBING
J 0
(2725 3500);
DISPLAY 0.872340 (2725 3500);
PAINT GREEN (2725 3500);
DISPLAY INVISIBLE (2725 3500);
FORCEPROP 1 LAST HDL_TAP TRUE
J 0
(3050 3325);
DISPLAY 0.872340 (3050 3325);
DISPLAY INVISIBLE (3050 3325);
FORCEPROP 1 LAST PATH I149
J 0
(2723 3450);
DISPLAY 0.872340 (2723 3450);
PAINT GREEN (2723 3450);
DISPLAY INVISIBLE (2723 3450);
FORCEADD TAP..1
R 2
(-700 350);
FORCEPROP 3 LASTPIN (-650 350) SIG_NAME M_E_CPU0_SB_CB<6>
J 0
(-640 360);
DISPLAY 0.659574 (-640 360);
PAINT MONO (-640 360);
DISPLAY INVISIBLE (-640 360);
FORCEPROP 1 LASTPIN (-650 350) BN 6
J 2
(-638 358);
DISPLAY 0.680851 (-638 358);
PAINT GREEN (-638 358);
FORCEPROP 2 LAST CDS_LIB standard
J 0
(-700 350);
DISPLAY INVISIBLE (-700 350);
FORCEPROP 1 LAST BODY_TYPE PLUMBING
J 2
(-700 400);
DISPLAY 0.872340 (-700 400);
PAINT GREEN (-700 400);
DISPLAY INVISIBLE (-700 400);
FORCEPROP 1 LAST HDL_TAP TRUE
J 2
(-1025 225);
DISPLAY 0.872340 (-1025 225);
DISPLAY INVISIBLE (-1025 225);
FORCEPROP 1 LAST PATH I15
J 2
(-698 350);
DISPLAY 0.872340 (-698 350);
PAINT GREEN (-698 350);
DISPLAY INVISIBLE (-698 350);
FORCEADD TAP..1
(2725 3650);
FORCEPROP 3 LASTPIN (2675 3650) SIG_NAME M_E_CPU0_SA_DQS_DP<2>
J 0
(2685 3660);
DISPLAY 0.659574 (2685 3660);
PAINT MONO (2685 3660);
DISPLAY INVISIBLE (2685 3660);
FORCEPROP 1 LASTPIN (2675 3650) BN 2
J 0
(2663 3658);
DISPLAY 0.680851 (2663 3658);
PAINT GREEN (2663 3658);
FORCEPROP 2 LAST CDS_LIB standard
J 0
(2725 3650);
DISPLAY INVISIBLE (2725 3650);
FORCEPROP 1 LAST BODY_TYPE PLUMBING
J 0
(2725 3700);
DISPLAY 0.872340 (2725 3700);
PAINT GREEN (2725 3700);
DISPLAY INVISIBLE (2725 3700);
FORCEPROP 1 LAST HDL_TAP TRUE
J 0
(3050 3525);
DISPLAY 0.872340 (3050 3525);
DISPLAY INVISIBLE (3050 3525);
FORCEPROP 1 LAST PATH I150
J 0
(2723 3650);
DISPLAY 0.872340 (2723 3650);
PAINT GREEN (2723 3650);
DISPLAY INVISIBLE (2723 3650);
FORCEADD TAP..1
(2725 3600);
FORCEPROP 3 LASTPIN (2675 3600) SIG_NAME M_E_CPU0_SA_DQS_DP<1>
J 0
(2685 3610);
DISPLAY 0.659574 (2685 3610);
PAINT MONO (2685 3610);
DISPLAY INVISIBLE (2685 3610);
FORCEPROP 1 LASTPIN (2675 3600) BN 1
J 0
(2663 3608);
DISPLAY 0.680851 (2663 3608);
PAINT GREEN (2663 3608);
FORCEPROP 2 LAST CDS_LIB standard
J 0
(2725 3600);
DISPLAY INVISIBLE (2725 3600);
FORCEPROP 1 LAST BODY_TYPE PLUMBING
J 0
(2725 3650);
DISPLAY 0.872340 (2725 3650);
PAINT GREEN (2725 3650);
DISPLAY INVISIBLE (2725 3650);
FORCEPROP 1 LAST HDL_TAP TRUE
J 0
(3050 3475);
DISPLAY 0.872340 (3050 3475);
DISPLAY INVISIBLE (3050 3475);
FORCEPROP 1 LAST PATH I151
J 0
(2723 3600);
DISPLAY 0.872340 (2723 3600);
PAINT GREEN (2723 3600);
DISPLAY INVISIBLE (2723 3600);
FORCEADD TAP..1
(2725 3750);
FORCEPROP 3 LASTPIN (2675 3750) SIG_NAME M_E_CPU0_SA_DQS_DP<4>
J 0
(2685 3760);
DISPLAY 0.659574 (2685 3760);
PAINT MONO (2685 3760);
DISPLAY INVISIBLE (2685 3760);
FORCEPROP 1 LASTPIN (2675 3750) BN 4
J 0
(2663 3758);
DISPLAY 0.680851 (2663 3758);
PAINT GREEN (2663 3758);
FORCEPROP 2 LAST CDS_LIB standard
J 0
(2725 3750);
DISPLAY INVISIBLE (2725 3750);
FORCEPROP 1 LAST BODY_TYPE PLUMBING
J 0
(2725 3800);
DISPLAY 0.872340 (2725 3800);
PAINT GREEN (2725 3800);
DISPLAY INVISIBLE (2725 3800);
FORCEPROP 1 LAST HDL_TAP TRUE
J 0
(3050 3625);
DISPLAY 0.872340 (3050 3625);
DISPLAY INVISIBLE (3050 3625);
FORCEPROP 1 LAST PATH I152
J 0
(2723 3750);
DISPLAY 0.872340 (2723 3750);
PAINT GREEN (2723 3750);
DISPLAY INVISIBLE (2723 3750);
FORCEADD TAP..1
(2725 3800);
FORCEPROP 3 LASTPIN (2675 3800) SIG_NAME M_E_CPU0_SA_DQS_DP<5>
J 0
(2685 3810);
DISPLAY 0.659574 (2685 3810);
PAINT MONO (2685 3810);
DISPLAY INVISIBLE (2685 3810);
FORCEPROP 1 LASTPIN (2675 3800) BN 5
J 0
(2663 3808);
DISPLAY 0.680851 (2663 3808);
PAINT GREEN (2663 3808);
FORCEPROP 2 LAST CDS_LIB standard
J 0
(2725 3800);
DISPLAY INVISIBLE (2725 3800);
FORCEPROP 1 LAST BODY_TYPE PLUMBING
J 0
(2725 3850);
DISPLAY 0.872340 (2725 3850);
PAINT GREEN (2725 3850);
DISPLAY INVISIBLE (2725 3850);
FORCEPROP 1 LAST HDL_TAP TRUE
J 0
(3050 3675);
DISPLAY 0.872340 (3050 3675);
DISPLAY INVISIBLE (3050 3675);
FORCEPROP 1 LAST PATH I153
J 0
(2723 3800);
DISPLAY 0.872340 (2723 3800);
PAINT GREEN (2723 3800);
DISPLAY INVISIBLE (2723 3800);
FORCEADD TAP..1
(2725 3700);
FORCEPROP 3 LASTPIN (2675 3700) SIG_NAME M_E_CPU0_SA_DQS_DP<3>
J 0
(2685 3710);
DISPLAY 0.659574 (2685 3710);
PAINT MONO (2685 3710);
DISPLAY INVISIBLE (2685 3710);
FORCEPROP 1 LASTPIN (2675 3700) BN 3
J 0
(2663 3708);
DISPLAY 0.680851 (2663 3708);
PAINT GREEN (2663 3708);
FORCEPROP 2 LAST CDS_LIB standard
J 0
(2725 3700);
DISPLAY INVISIBLE (2725 3700);
FORCEPROP 1 LAST BODY_TYPE PLUMBING
J 0
(2725 3750);
DISPLAY 0.872340 (2725 3750);
PAINT GREEN (2725 3750);
DISPLAY INVISIBLE (2725 3750);
FORCEPROP 1 LAST HDL_TAP TRUE
J 0
(3050 3575);
DISPLAY 0.872340 (3050 3575);
DISPLAY INVISIBLE (3050 3575);
FORCEPROP 1 LAST PATH I154
J 0
(2723 3700);
DISPLAY 0.872340 (2723 3700);
PAINT GREEN (2723 3700);
DISPLAY INVISIBLE (2723 3700);
FORCEADD TAP..1
(2725 3900);
FORCEPROP 3 LASTPIN (2675 3900) SIG_NAME M_E_CPU0_SA_DQS_DP<7>
J 0
(2685 3910);
DISPLAY 0.659574 (2685 3910);
PAINT MONO (2685 3910);
DISPLAY INVISIBLE (2685 3910);
FORCEPROP 1 LASTPIN (2675 3900) BN 7
J 0
(2663 3908);
DISPLAY 0.680851 (2663 3908);
PAINT GREEN (2663 3908);
FORCEPROP 2 LAST CDS_LIB standard
J 0
(2725 3900);
DISPLAY INVISIBLE (2725 3900);
FORCEPROP 1 LAST BODY_TYPE PLUMBING
J 0
(2725 3950);
DISPLAY 0.872340 (2725 3950);
PAINT GREEN (2725 3950);
DISPLAY INVISIBLE (2725 3950);
FORCEPROP 1 LAST HDL_TAP TRUE
J 0
(3050 3775);
DISPLAY 0.872340 (3050 3775);
DISPLAY INVISIBLE (3050 3775);
FORCEPROP 1 LAST PATH I155
J 0
(2723 3900);
DISPLAY 0.872340 (2723 3900);
PAINT GREEN (2723 3900);
DISPLAY INVISIBLE (2723 3900);
FORCEADD TAP..1
(2725 3850);
FORCEPROP 3 LASTPIN (2675 3850) SIG_NAME M_E_CPU0_SA_DQS_DP<6>
J 0
(2685 3860);
DISPLAY 0.659574 (2685 3860);
PAINT MONO (2685 3860);
DISPLAY INVISIBLE (2685 3860);
FORCEPROP 1 LASTPIN (2675 3850) BN 6
J 0
(2663 3858);
DISPLAY 0.680851 (2663 3858);
PAINT GREEN (2663 3858);
FORCEPROP 2 LAST CDS_LIB standard
J 0
(2725 3850);
DISPLAY INVISIBLE (2725 3850);
FORCEPROP 1 LAST BODY_TYPE PLUMBING
J 0
(2725 3900);
DISPLAY 0.872340 (2725 3900);
PAINT GREEN (2725 3900);
DISPLAY INVISIBLE (2725 3900);
FORCEPROP 1 LAST HDL_TAP TRUE
J 0
(3050 3725);
DISPLAY 0.872340 (3050 3725);
DISPLAY INVISIBLE (3050 3725);
FORCEPROP 1 LAST PATH I156
J 0
(2723 3850);
DISPLAY 0.872340 (2723 3850);
PAINT GREEN (2723 3850);
DISPLAY INVISIBLE (2723 3850);
FORCEADD TAP..1
(2725 4000);
FORCEPROP 3 LASTPIN (2675 4000) SIG_NAME M_E_CPU0_SA_DQS_DP<9>
J 0
(2685 4010);
DISPLAY 0.659574 (2685 4010);
PAINT MONO (2685 4010);
DISPLAY INVISIBLE (2685 4010);
FORCEPROP 1 LASTPIN (2675 4000) BN 9
J 0
(2663 4008);
DISPLAY 0.680851 (2663 4008);
PAINT GREEN (2663 4008);
FORCEPROP 2 LAST CDS_LIB standard
J 0
(2725 4000);
DISPLAY INVISIBLE (2725 4000);
FORCEPROP 1 LAST BODY_TYPE PLUMBING
J 0
(2725 4050);
DISPLAY 0.872340 (2725 4050);
PAINT GREEN (2725 4050);
DISPLAY INVISIBLE (2725 4050);
FORCEPROP 1 LAST HDL_TAP TRUE
J 0
(3050 3875);
DISPLAY 0.872340 (3050 3875);
DISPLAY INVISIBLE (3050 3875);
FORCEPROP 1 LAST PATH I157
J 0
(2723 4000);
DISPLAY 0.872340 (2723 4000);
PAINT GREEN (2723 4000);
DISPLAY INVISIBLE (2723 4000);
FORCEADD TAP..1
(2725 3950);
FORCEPROP 3 LASTPIN (2675 3950) SIG_NAME M_E_CPU0_SA_DQS_DP<8>
J 0
(2685 3960);
DISPLAY 0.659574 (2685 3960);
PAINT MONO (2685 3960);
DISPLAY INVISIBLE (2685 3960);
FORCEPROP 1 LASTPIN (2675 3950) BN 8
J 0
(2663 3958);
DISPLAY 0.680851 (2663 3958);
PAINT GREEN (2663 3958);
FORCEPROP 2 LAST CDS_LIB standard
J 0
(2725 3950);
DISPLAY INVISIBLE (2725 3950);
FORCEPROP 1 LAST BODY_TYPE PLUMBING
J 0
(2725 4000);
DISPLAY 0.872340 (2725 4000);
PAINT GREEN (2725 4000);
DISPLAY INVISIBLE (2725 4000);
FORCEPROP 1 LAST HDL_TAP TRUE
J 0
(3050 3825);
DISPLAY 0.872340 (3050 3825);
DISPLAY INVISIBLE (3050 3825);
FORCEPROP 1 LAST PATH I158
J 0
(2723 3950);
DISPLAY 0.872340 (2723 3950);
PAINT GREEN (2723 3950);
DISPLAY INVISIBLE (2723 3950);
FORCEADD OFFPAGE..2
(3825 425);
FORCEPROP 2 LAST $XR1 91 
J 0
(4104 425);
DISPLAY 0.638298 (4104 425);
PAINT MONO (4104 425);
FORCEPROP 2 LAST $XR0 90 
J 0
(4014 425);
DISPLAY 0.638298 (4014 425);
PAINT MONO (4014 425);
FORCEPROP 2 LAST CDS_LIB standard
J 0
(3825 425);
PAINT MONO (3825 425);
DISPLAY INVISIBLE (3825 425);
FORCEPROP 1 LAST OFFPAGE TRUE
J 0
(4150 300);
DISPLAY 1.170213 (4150 300);
PAINT GREEN (4150 300);
DISPLAY INVISIBLE (4150 300);
FORCEPROP 1 LAST COMMENT_BODY TRUE
J 0
(3780 330);
DISPLAY 1.170213 (3780 330);
PAINT GREEN (3780 330);
DISPLAY INVISIBLE (3780 330);
FORCEPROP 2 LAST PATH I159
J 0
(4000 500);
DISPLAY 1.021277 (4000 500);
DISPLAY INVISIBLE (4000 500);
FORCEADD TAP..1
R 2
(-700 400);
FORCEPROP 3 LASTPIN (-650 400) SIG_NAME M_E_CPU0_SB_CB<7>
J 0
(-640 410);
DISPLAY 0.659574 (-640 410);
PAINT MONO (-640 410);
DISPLAY INVISIBLE (-640 410);
FORCEPROP 1 LASTPIN (-650 400) BN 7
J 2
(-638 408);
DISPLAY 0.680851 (-638 408);
PAINT GREEN (-638 408);
FORCEPROP 2 LAST CDS_LIB standard
J 0
(-700 400);
DISPLAY INVISIBLE (-700 400);
FORCEPROP 1 LAST BODY_TYPE PLUMBING
J 2
(-700 450);
DISPLAY 0.872340 (-700 450);
PAINT GREEN (-700 450);
DISPLAY INVISIBLE (-700 450);
FORCEPROP 1 LAST HDL_TAP TRUE
J 2
(-1025 275);
DISPLAY 0.872340 (-1025 275);
DISPLAY INVISIBLE (-1025 275);
FORCEPROP 1 LAST PATH I16
J 2
(-698 400);
DISPLAY 0.872340 (-698 400);
PAINT GREEN (-698 400);
DISPLAY INVISIBLE (-698 400);
FORCEADD OFFPAGE..2
(3825 725);
FORCEPROP 2 LAST $XR1 91 
J 0
(4104 725);
DISPLAY 0.638298 (4104 725);
PAINT MONO (4104 725);
FORCEPROP 2 LAST $XR0 90 
J 0
(4014 725);
DISPLAY 0.638298 (4014 725);
PAINT MONO (4014 725);
FORCEPROP 2 LAST CDS_LIB standard
J 0
(3825 725);
PAINT MONO (3825 725);
DISPLAY INVISIBLE (3825 725);
FORCEPROP 1 LAST OFFPAGE TRUE
J 0
(4150 600);
DISPLAY 1.170213 (4150 600);
PAINT GREEN (4150 600);
DISPLAY INVISIBLE (4150 600);
FORCEPROP 1 LAST COMMENT_BODY TRUE
J 0
(3780 630);
DISPLAY 1.170213 (3780 630);
PAINT GREEN (3780 630);
DISPLAY INVISIBLE (3780 630);
FORCEPROP 2 LAST PATH I160
J 0
(4000 800);
DISPLAY 1.021277 (4000 800);
DISPLAY INVISIBLE (4000 800);
FORCEADD OFFPAGE..2
(3825 850);
FORCEPROP 2 LAST $XR1 91 
J 0
(4104 850);
DISPLAY 0.638298 (4104 850);
PAINT MONO (4104 850);
FORCEPROP 2 LAST $XR0 90 
J 0
(4014 850);
DISPLAY 0.638298 (4014 850);
PAINT MONO (4014 850);
FORCEPROP 2 LAST CDS_LIB standard
J 0
(3825 850);
PAINT MONO (3825 850);
DISPLAY INVISIBLE (3825 850);
FORCEPROP 1 LAST OFFPAGE TRUE
J 0
(4150 725);
DISPLAY 1.170213 (4150 725);
PAINT GREEN (4150 725);
DISPLAY INVISIBLE (4150 725);
FORCEPROP 1 LAST COMMENT_BODY TRUE
J 0
(3780 755);
DISPLAY 1.170213 (3780 755);
PAINT GREEN (3780 755);
DISPLAY INVISIBLE (3780 755);
FORCEPROP 2 LAST PATH I161
J 0
(4000 925);
DISPLAY 1.021277 (4000 925);
DISPLAY INVISIBLE (4000 925);
FORCEADD OFFPAGE..3
(3825 1225);
FORCEPROP 2 LAST $XR1 91 
J 0
(4129 1225);
DISPLAY 0.638298 (4129 1225);
PAINT MONO (4129 1225);
FORCEPROP 2 LAST $XR0 90 
J 0
(4039 1225);
DISPLAY 0.638298 (4039 1225);
PAINT MONO (4039 1225);
FORCEPROP 2 LAST CDS_LIB standard
J 2
(3825 1225);
DISPLAY INVISIBLE (3825 1225);
FORCEPROP 1 LAST OFFPAGE TRUE
J 0
(4150 1100);
DISPLAY 0.872340 (4150 1100);
DISPLAY INVISIBLE (4150 1100);
FORCEPROP 1 LAST COMMENT_BODY TRUE
J 0
(3775 1125);
DISPLAY 0.872340 (3775 1125);
PAINT GREEN (3775 1125);
DISPLAY INVISIBLE (3775 1125);
FORCEPROP 2 LAST PATH I162
J 0
(4025 1300);
DISPLAY 1.021277 (4025 1300);
DISPLAY INVISIBLE (4025 1300);
FORCEADD OFFPAGE..2
(3825 1350);
FORCEPROP 2 LAST $XR1 91 
J 0
(4104 1350);
DISPLAY 0.638298 (4104 1350);
PAINT MONO (4104 1350);
FORCEPROP 2 LAST $XR0 90 
J 0
(4014 1350);
DISPLAY 0.638298 (4014 1350);
PAINT MONO (4014 1350);
FORCEPROP 2 LAST CDS_LIB standard
J 0
(3825 1350);
PAINT MONO (3825 1350);
DISPLAY INVISIBLE (3825 1350);
FORCEPROP 1 LAST OFFPAGE TRUE
J 0
(4150 1225);
DISPLAY 1.170213 (4150 1225);
PAINT GREEN (4150 1225);
DISPLAY INVISIBLE (4150 1225);
FORCEPROP 1 LAST COMMENT_BODY TRUE
J 0
(3780 1255);
DISPLAY 1.170213 (3780 1255);
PAINT GREEN (3780 1255);
DISPLAY INVISIBLE (3780 1255);
FORCEPROP 2 LAST PATH I163
J 0
(4000 1425);
DISPLAY 1.021277 (4000 1425);
DISPLAY INVISIBLE (4000 1425);
FORCEADD OFFPAGE..3
(3825 1725);
FORCEPROP 2 LAST $XR1 91 
J 0
(4129 1725);
DISPLAY 0.638298 (4129 1725);
PAINT MONO (4129 1725);
FORCEPROP 2 LAST $XR0 90 
J 0
(4039 1725);
DISPLAY 0.638298 (4039 1725);
PAINT MONO (4039 1725);
FORCEPROP 2 LAST CDS_LIB standard
J 2
(3825 1725);
DISPLAY INVISIBLE (3825 1725);
FORCEPROP 1 LAST OFFPAGE TRUE
J 0
(4150 1600);
DISPLAY 0.872340 (4150 1600);
DISPLAY INVISIBLE (4150 1600);
FORCEPROP 1 LAST COMMENT_BODY TRUE
J 0
(3775 1625);
DISPLAY 0.872340 (3775 1625);
PAINT GREEN (3775 1625);
DISPLAY INVISIBLE (3775 1625);
FORCEPROP 2 LAST PATH I164
J 0
(4025 1800);
DISPLAY 1.021277 (4025 1800);
DISPLAY INVISIBLE (4025 1800);
FORCEADD OFFPAGE..3
(3825 2325);
FORCEPROP 2 LAST $XR1 91 
J 0
(4129 2325);
DISPLAY 0.638298 (4129 2325);
PAINT MONO (4129 2325);
FORCEPROP 2 LAST $XR0 90 
J 0
(4039 2325);
DISPLAY 0.638298 (4039 2325);
PAINT MONO (4039 2325);
FORCEPROP 2 LAST CDS_LIB standard
J 2
(3825 2325);
DISPLAY INVISIBLE (3825 2325);
FORCEPROP 1 LAST OFFPAGE TRUE
J 0
(4150 2200);
DISPLAY 0.872340 (4150 2200);
DISPLAY INVISIBLE (4150 2200);
FORCEPROP 1 LAST COMMENT_BODY TRUE
J 0
(3775 2225);
DISPLAY 0.872340 (3775 2225);
PAINT GREEN (3775 2225);
DISPLAY INVISIBLE (3775 2225);
FORCEPROP 2 LAST PATH I165
J 0
(4025 2400);
DISPLAY 1.021277 (4025 2400);
DISPLAY INVISIBLE (4025 2400);
FORCEADD OFFPAGE..3
(3825 2875);
FORCEPROP 2 LAST $XR1 91 
J 0
(4129 2875);
DISPLAY 0.638298 (4129 2875);
PAINT MONO (4129 2875);
FORCEPROP 2 LAST $XR0 90 
J 0
(4039 2875);
DISPLAY 0.638298 (4039 2875);
PAINT MONO (4039 2875);
FORCEPROP 2 LAST CDS_LIB standard
J 2
(3825 2875);
DISPLAY INVISIBLE (3825 2875);
FORCEPROP 1 LAST OFFPAGE TRUE
J 0
(4150 2750);
DISPLAY 0.872340 (4150 2750);
DISPLAY INVISIBLE (4150 2750);
FORCEPROP 1 LAST COMMENT_BODY TRUE
J 0
(3775 2775);
DISPLAY 0.872340 (3775 2775);
PAINT GREEN (3775 2775);
DISPLAY INVISIBLE (3775 2775);
FORCEPROP 2 LAST PATH I166
J 0
(4025 2950);
DISPLAY 1.021277 (4025 2950);
DISPLAY INVISIBLE (4025 2950);
FORCEADD OFFPAGE..3
(3825 3475);
FORCEPROP 2 LAST $XR1 91 
J 0
(4129 3475);
DISPLAY 0.638298 (4129 3475);
PAINT MONO (4129 3475);
FORCEPROP 2 LAST $XR0 90 
J 0
(4039 3475);
DISPLAY 0.638298 (4039 3475);
PAINT MONO (4039 3475);
FORCEPROP 2 LAST CDS_LIB standard
J 2
(3825 3475);
DISPLAY INVISIBLE (3825 3475);
FORCEPROP 1 LAST OFFPAGE TRUE
J 0
(4150 3350);
DISPLAY 0.872340 (4150 3350);
DISPLAY INVISIBLE (4150 3350);
FORCEPROP 1 LAST COMMENT_BODY TRUE
J 0
(3775 3375);
DISPLAY 0.872340 (3775 3375);
PAINT GREEN (3775 3375);
DISPLAY INVISIBLE (3775 3375);
FORCEPROP 2 LAST PATH I167
J 0
(4025 3550);
DISPLAY 1.021277 (4025 3550);
DISPLAY INVISIBLE (4025 3550);
FORCEADD OFFPAGE..3
(3825 4025);
FORCEPROP 2 LAST $XR1 91 
J 0
(4129 4025);
DISPLAY 0.638298 (4129 4025);
PAINT MONO (4129 4025);
FORCEPROP 2 LAST $XR0 90 
J 0
(4039 4025);
DISPLAY 0.638298 (4039 4025);
PAINT MONO (4039 4025);
FORCEPROP 2 LAST CDS_LIB standard
J 2
(3825 4025);
DISPLAY INVISIBLE (3825 4025);
FORCEPROP 1 LAST OFFPAGE TRUE
J 0
(4150 3900);
DISPLAY 0.872340 (4150 3900);
DISPLAY INVISIBLE (4150 3900);
FORCEPROP 1 LAST COMMENT_BODY TRUE
J 0
(3775 3925);
DISPLAY 0.872340 (3775 3925);
PAINT GREEN (3775 3925);
DISPLAY INVISIBLE (3775 3925);
FORCEPROP 2 LAST PATH I168
J 0
(4025 4100);
DISPLAY 1.021277 (4025 4100);
DISPLAY INVISIBLE (4025 4100);
FORCEADD SOCKET4677_AZIF0045P001C01CS..12
(1025 1900);
FORCEPROP 1 LAST PART_NUMBER DGA^7000023
J 0
(-75 4250);
DISPLAY 0.723404 (-75 4250);
PAINT GREEN (-75 4250);
DISPLAY INVISIBLE (-75 4250);
FORCEPROP 2 LAST PART_TYPE SMLF
J 0
(-75 4425);
DISPLAY 1.021277 (-75 4425);
FORCEPROP 1 LAST MATERIAL IO
J 0
(-75 4175);
DISPLAY 0.723404 (-75 4175);
PAINT GREEN (-75 4175);
FORCEPROP 2 LAST VALUE SOCKET4677_AZIF0045-P001C01CS
J 0
(-75 4375);
DISPLAY 1.021277 (-75 4375);
FORCEPROP 1 LAST $LOCATION U2
J 0
(-75 4325);
DISPLAY 0.723404 (-75 4325);
PAINT GREEN (-75 4325);
FORCEPROP 0 LASTPIN (2250 50) $PN DD44
J 0
(2260 60);
DISPLAY 0.680851 (2260 60);
PAINT MONO (2260 60);
FORCEPROP 0 LASTPIN (2250 100) $PN DC43
J 0
(2260 110);
DISPLAY 0.680851 (2260 110);
PAINT MONO (2260 110);
FORCEPROP 0 LASTPIN (2250 -200) $PN CY47
J 0
(2260 -190);
DISPLAY 0.680851 (2260 -190);
PAINT MONO (2260 -190);
FORCEPROP 0 LASTPIN (2250 -100) $PN DF44
J 0
(2260 -90);
DISPLAY 0.680851 (2260 -90);
PAINT MONO (2260 -90);
FORCEPROP 0 LASTPIN (2250 -50) $PN DG43
J 0
(2260 -40);
DISPLAY 0.680851 (2260 -40);
PAINT MONO (2260 -40);
FORCEPROP 0 LASTPIN (-200 -200) $PN EJ45
J 2
(-210 -190);
DISPLAY 0.680851 (-210 -190);
PAINT MONO (-210 -190);
FORCEPROP 0 LASTPIN (-200 -150) $PN EE45
J 2
(-210 -140);
DISPLAY 0.680851 (-210 -140);
PAINT MONO (-210 -140);
FORCEPROP 0 LASTPIN (-200 -100) $PN EG45
J 2
(-210 -90);
DISPLAY 0.680851 (-210 -90);
PAINT MONO (-210 -90);
FORCEPROP 0 LASTPIN (-200 -50) $PN EC45
J 2
(-210 -40);
DISPLAY 0.680851 (-210 -40);
PAINT MONO (-210 -40);
FORCEPROP 0 LASTPIN (2250 1400) $PN EP49
J 0
(2260 1410);
DISPLAY 0.680851 (2260 1410);
PAINT MONO (2260 1410);
FORCEPROP 0 LASTPIN (2250 1450) $PN ET49
J 0
(2260 1460);
DISPLAY 0.680851 (2260 1460);
PAINT MONO (2260 1460);
FORCEPROP 0 LASTPIN (2250 1500) $PN EK49
J 0
(2260 1510);
DISPLAY 0.680851 (2260 1510);
PAINT MONO (2260 1510);
FORCEPROP 0 LASTPIN (2250 1550) $PN EL48
J 0
(2260 1560);
DISPLAY 0.680851 (2260 1560);
PAINT MONO (2260 1560);
FORCEPROP 0 LASTPIN (2250 1600) $PN EM47
J 0
(2260 1610);
DISPLAY 0.680851 (2260 1610);
PAINT MONO (2260 1610);
FORCEPROP 0 LASTPIN (2250 1650) $PN EP47
J 0
(2260 1660);
DISPLAY 0.680851 (2260 1660);
PAINT MONO (2260 1660);
FORCEPROP 0 LASTPIN (2250 1700) $PN ED44
J 0
(2260 1710);
DISPLAY 0.680851 (2260 1710);
PAINT MONO (2260 1710);
FORCEPROP 0 LASTPIN (-200 2450) $PN EL78
J 2
(-210 2460);
DISPLAY 0.680851 (-210 2460);
PAINT MONO (-210 2460);
FORCEPROP 0 LASTPIN (-200 2500) $PN EM77
J 2
(-210 2510);
DISPLAY 0.680851 (-210 2510);
PAINT MONO (-210 2510);
FORCEPROP 0 LASTPIN (-200 2550) $PN EP79
J 2
(-210 2560);
DISPLAY 0.680851 (-210 2560);
PAINT MONO (-210 2560);
FORCEPROP 0 LASTPIN (-200 2600) $PN ER76
J 2
(-210 2610);
DISPLAY 0.680851 (-210 2610);
PAINT MONO (-210 2610);
FORCEPROP 0 LASTPIN (-200 2650) $PN EL74
J 2
(-210 2660);
DISPLAY 0.680851 (-210 2660);
PAINT MONO (-210 2660);
FORCEPROP 0 LASTPIN (-200 2700) $PN EK73
J 2
(-210 2710);
DISPLAY 0.680851 (-210 2710);
PAINT MONO (-210 2710);
FORCEPROP 0 LASTPIN (-200 2750) $PN EP73
J 2
(-210 2760);
DISPLAY 0.680851 (-210 2760);
PAINT MONO (-210 2760);
FORCEPROP 0 LASTPIN (-200 2800) $PN ER72
J 2
(-210 2810);
DISPLAY 0.680851 (-210 2810);
PAINT MONO (-210 2810);
FORCEPROP 0 LASTPIN (-200 2850) $PN EE72
J 2
(-210 2860);
DISPLAY 0.680851 (-210 2860);
PAINT MONO (-210 2860);
FORCEPROP 0 LASTPIN (-200 2900) $PN ED71
J 2
(-210 2910);
DISPLAY 0.680851 (-210 2910);
PAINT MONO (-210 2910);
FORCEPROP 0 LASTPIN (-200 2950) $PN EG72
J 2
(-210 2960);
DISPLAY 0.680851 (-210 2960);
PAINT MONO (-210 2960);
FORCEPROP 0 LASTPIN (-200 3000) $PN EH71
J 2
(-210 3010);
DISPLAY 0.680851 (-210 3010);
PAINT MONO (-210 3010);
FORCEPROP 0 LASTPIN (-200 3050) $PN ED69
J 2
(-210 3060);
DISPLAY 0.680851 (-210 3060);
PAINT MONO (-210 3060);
FORCEPROP 0 LASTPIN (-200 3100) $PN EE68
J 2
(-210 3110);
DISPLAY 0.680851 (-210 3110);
PAINT MONO (-210 3110);
FORCEPROP 0 LASTPIN (-200 3150) $PN EH69
J 2
(-210 3160);
DISPLAY 0.680851 (-210 3160);
PAINT MONO (-210 3160);
FORCEPROP 0 LASTPIN (-200 3200) $PN EG68
J 2
(-210 3210);
DISPLAY 0.680851 (-210 3210);
PAINT MONO (-210 3210);
FORCEPROP 0 LASTPIN (-200 3250) $PN EM71
J 2
(-210 3260);
DISPLAY 0.680851 (-210 3260);
PAINT MONO (-210 3260);
FORCEPROP 0 LASTPIN (-200 3300) $PN EM69
J 2
(-210 3310);
DISPLAY 0.680851 (-210 3310);
PAINT MONO (-210 3310);
FORCEPROP 0 LASTPIN (-200 3350) $PN EN70
J 2
(-210 3360);
DISPLAY 0.680851 (-210 3360);
PAINT MONO (-210 3360);
FORCEPROP 0 LASTPIN (-200 3400) $PN ER68
J 2
(-210 3410);
DISPLAY 0.680851 (-210 3410);
PAINT MONO (-210 3410);
FORCEPROP 0 LASTPIN (-200 3450) $PN ER66
J 2
(-210 3460);
DISPLAY 0.680851 (-210 3460);
PAINT MONO (-210 3460);
FORCEPROP 0 LASTPIN (-200 3500) $PN EM65
J 2
(-210 3510);
DISPLAY 0.680851 (-210 3510);
PAINT MONO (-210 3510);
FORCEPROP 0 LASTPIN (-200 3550) $PN EL66
J 2
(-210 3560);
DISPLAY 0.680851 (-210 3560);
PAINT MONO (-210 3560);
FORCEPROP 0 LASTPIN (-200 3600) $PN EP65
J 2
(-210 3610);
DISPLAY 0.680851 (-210 3610);
PAINT MONO (-210 3610);
FORCEPROP 0 LASTPIN (-200 3650) $PN EM63
J 2
(-210 3660);
DISPLAY 0.680851 (-210 3660);
PAINT MONO (-210 3660);
FORCEPROP 0 LASTPIN (-200 3700) $PN EL62
J 2
(-210 3710);
DISPLAY 0.680851 (-210 3710);
PAINT MONO (-210 3710);
FORCEPROP 0 LASTPIN (-200 3750) $PN EP63
J 2
(-210 3760);
DISPLAY 0.680851 (-210 3760);
PAINT MONO (-210 3760);
FORCEPROP 0 LASTPIN (-200 3800) $PN ER62
J 2
(-210 3810);
DISPLAY 0.680851 (-210 3810);
PAINT MONO (-210 3810);
FORCEPROP 0 LASTPIN (-200 3850) $PN EL60
J 2
(-210 3860);
DISPLAY 0.680851 (-210 3860);
PAINT MONO (-210 3860);
FORCEPROP 0 LASTPIN (-200 3900) $PN EM59
J 2
(-210 3910);
DISPLAY 0.680851 (-210 3910);
PAINT MONO (-210 3910);
FORCEPROP 0 LASTPIN (-200 3950) $PN ER60
J 2
(-210 3960);
DISPLAY 0.680851 (-210 3960);
PAINT MONO (-210 3960);
FORCEPROP 0 LASTPIN (-200 4000) $PN EP59
J 2
(-210 4010);
DISPLAY 0.680851 (-210 4010);
PAINT MONO (-210 4010);
FORCEPROP 0 LASTPIN (2250 3000) $PN EP75
J 0
(2260 3010);
DISPLAY 0.680851 (2260 3010);
PAINT MONO (2260 3010);
FORCEPROP 0 LASTPIN (2250 3050) $PN EC70
J 0
(2260 3060);
DISPLAY 0.680851 (2260 3060);
PAINT MONO (2260 3060);
FORCEPROP 0 LASTPIN (2250 3100) $PN EK67
J 0
(2260 3110);
DISPLAY 0.680851 (2260 3110);
PAINT MONO (2260 3110);
FORCEPROP 0 LASTPIN (2250 3150) $PN EK61
J 0
(2260 3160);
DISPLAY 0.680851 (2260 3160);
PAINT MONO (2260 3160);
FORCEPROP 0 LASTPIN (2250 3200) $PN EM55
J 0
(2260 3210);
DISPLAY 0.680851 (2260 3210);
PAINT MONO (2260 3210);
FORCEPROP 0 LASTPIN (2250 3250) $PN EM75
J 0
(2260 3260);
DISPLAY 0.680851 (2260 3260);
PAINT MONO (2260 3260);
FORCEPROP 0 LASTPIN (2250 3300) $PN EJ70
J 0
(2260 3310);
DISPLAY 0.680851 (2260 3310);
PAINT MONO (2260 3310);
FORCEPROP 0 LASTPIN (2250 3350) $PN EN68
J 0
(2260 3360);
DISPLAY 0.680851 (2260 3360);
PAINT MONO (2260 3360);
FORCEPROP 0 LASTPIN (2250 3400) $PN ET61
J 0
(2260 3410);
DISPLAY 0.680851 (2260 3410);
PAINT MONO (2260 3410);
FORCEPROP 0 LASTPIN (2250 3450) $PN ET55
J 0
(2260 3460);
DISPLAY 0.680851 (2260 3460);
PAINT MONO (2260 3460);
FORCEPROP 0 LASTPIN (2250 3550) $PN EN76
J 0
(2260 3560);
DISPLAY 0.680851 (2260 3560);
PAINT MONO (2260 3560);
FORCEPROP 0 LASTPIN (2250 3600) $PN EE70
J 0
(2260 3610);
DISPLAY 0.680851 (2260 3610);
PAINT MONO (2260 3610);
FORCEPROP 0 LASTPIN (2250 3650) $PN EL68
J 0
(2260 3660);
DISPLAY 0.680851 (2260 3660);
PAINT MONO (2260 3660);
FORCEPROP 0 LASTPIN (2250 3700) $PN EM61
J 0
(2260 3710);
DISPLAY 0.680851 (2260 3710);
PAINT MONO (2260 3710);
FORCEPROP 0 LASTPIN (2250 3750) $PN EK55
J 0
(2260 3760);
DISPLAY 0.680851 (2260 3760);
PAINT MONO (2260 3760);
FORCEPROP 0 LASTPIN (2250 3800) $PN EN74
J 0
(2260 3810);
DISPLAY 0.680851 (2260 3810);
PAINT MONO (2260 3810);
FORCEPROP 0 LASTPIN (2250 3850) $PN EG70
J 0
(2260 3860);
DISPLAY 0.680851 (2260 3860);
PAINT MONO (2260 3860);
FORCEPROP 0 LASTPIN (2250 3900) $PN EM67
J 0
(2260 3910);
DISPLAY 0.680851 (2260 3910);
PAINT MONO (2260 3910);
FORCEPROP 0 LASTPIN (2250 3950) $PN EP61
J 0
(2260 3960);
DISPLAY 0.680851 (2260 3960);
PAINT MONO (2260 3960);
FORCEPROP 0 LASTPIN (2250 4000) $PN EP55
J 0
(2260 4010);
DISPLAY 0.680851 (2260 4010);
PAINT MONO (2260 4010);
FORCEPROP 0 LASTPIN (-200 2050) $PN EM57
J 2
(-210 2060);
DISPLAY 0.680851 (-210 2060);
PAINT MONO (-210 2060);
FORCEPROP 0 LASTPIN (-200 2100) $PN EL56
J 2
(-210 2110);
DISPLAY 0.680851 (-210 2110);
PAINT MONO (-210 2110);
FORCEPROP 0 LASTPIN (-200 2150) $PN EP57
J 2
(-210 2160);
DISPLAY 0.680851 (-210 2160);
PAINT MONO (-210 2160);
FORCEPROP 0 LASTPIN (-200 2200) $PN ER56
J 2
(-210 2210);
DISPLAY 0.680851 (-210 2210);
PAINT MONO (-210 2210);
FORCEPROP 0 LASTPIN (-200 2250) $PN EL54
J 2
(-210 2260);
DISPLAY 0.680851 (-210 2260);
PAINT MONO (-210 2260);
FORCEPROP 0 LASTPIN (-200 2300) $PN EM53
J 2
(-210 2310);
DISPLAY 0.680851 (-210 2310);
PAINT MONO (-210 2310);
FORCEPROP 0 LASTPIN (-200 2350) $PN ER54
J 2
(-210 2360);
DISPLAY 0.680851 (-210 2360);
PAINT MONO (-210 2360);
FORCEPROP 0 LASTPIN (-200 2400) $PN EP53
J 2
(-210 2410);
DISPLAY 0.680851 (-210 2410);
PAINT MONO (-210 2410);
FORCEPROP 0 LASTPIN (2250 1350) $PN EE43
J 0
(2260 1360);
DISPLAY 0.680851 (2260 1360);
PAINT MONO (2260 1360);
FORCEPROP 0 LASTPIN (2250 900) $PN EG43
J 0
(2260 910);
DISPLAY 0.680851 (2260 910);
PAINT MONO (2260 910);
FORCEPROP 0 LASTPIN (2250 950) $PN EH44
J 0
(2260 960);
DISPLAY 0.680851 (2260 960);
PAINT MONO (2260 960);
FORCEPROP 0 LASTPIN (2250 1000) $PN EM44
J 0
(2260 1010);
DISPLAY 0.680851 (2260 1010);
PAINT MONO (2260 1010);
FORCEPROP 0 LASTPIN (2250 1050) $PN EP44
J 0
(2260 1060);
DISPLAY 0.680851 (2260 1060);
PAINT MONO (2260 1060);
FORCEPROP 0 LASTPIN (2250 1100) $PN EL43
J 0
(2260 1110);
DISPLAY 0.680851 (2260 1110);
PAINT MONO (2260 1110);
FORCEPROP 0 LASTPIN (2250 1150) $PN ET42
J 0
(2260 1160);
DISPLAY 0.680851 (2260 1160);
PAINT MONO (2260 1160);
FORCEPROP 0 LASTPIN (2250 1200) $PN EK42
J 0
(2260 1210);
DISPLAY 0.680851 (2260 1210);
PAINT MONO (2260 1210);
FORCEPROP 0 LASTPIN (-200 450) $PN EE29
J 2
(-210 460);
DISPLAY 0.680851 (-210 460);
PAINT MONO (-210 460);
FORCEPROP 0 LASTPIN (-200 500) $PN ED28
J 2
(-210 510);
DISPLAY 0.680851 (-210 510);
PAINT MONO (-210 510);
FORCEPROP 0 LASTPIN (-200 550) $PN EG29
J 2
(-210 560);
DISPLAY 0.680851 (-210 560);
PAINT MONO (-210 560);
FORCEPROP 0 LASTPIN (-200 600) $PN EH28
J 2
(-210 610);
DISPLAY 0.680851 (-210 610);
PAINT MONO (-210 610);
FORCEPROP 0 LASTPIN (-200 650) $PN ED26
J 2
(-210 660);
DISPLAY 0.680851 (-210 660);
PAINT MONO (-210 660);
FORCEPROP 0 LASTPIN (-200 700) $PN EE25
J 2
(-210 710);
DISPLAY 0.680851 (-210 710);
PAINT MONO (-210 710);
FORCEPROP 0 LASTPIN (-200 750) $PN EH26
J 2
(-210 760);
DISPLAY 0.680851 (-210 760);
PAINT MONO (-210 760);
FORCEPROP 0 LASTPIN (-200 800) $PN EG25
J 2
(-210 810);
DISPLAY 0.680851 (-210 810);
PAINT MONO (-210 810);
FORCEPROP 0 LASTPIN (-200 850) $PN EM32
J 2
(-210 860);
DISPLAY 0.680851 (-210 860);
PAINT MONO (-210 860);
FORCEPROP 0 LASTPIN (-200 900) $PN EL31
J 2
(-210 910);
DISPLAY 0.680851 (-210 910);
PAINT MONO (-210 910);
FORCEPROP 0 LASTPIN (-200 950) $PN EP32
J 2
(-210 960);
DISPLAY 0.680851 (-210 960);
PAINT MONO (-210 960);
FORCEPROP 0 LASTPIN (-200 1000) $PN ER31
J 2
(-210 1010);
DISPLAY 0.680851 (-210 1010);
PAINT MONO (-210 1010);
FORCEPROP 0 LASTPIN (-200 1050) $PN EL29
J 2
(-210 1060);
DISPLAY 0.680851 (-210 1060);
PAINT MONO (-210 1060);
FORCEPROP 0 LASTPIN (-200 1100) $PN EM28
J 2
(-210 1110);
DISPLAY 0.680851 (-210 1110);
PAINT MONO (-210 1110);
FORCEPROP 0 LASTPIN (-200 1150) $PN ER29
J 2
(-210 1160);
DISPLAY 0.680851 (-210 1160);
PAINT MONO (-210 1160);
FORCEPROP 0 LASTPIN (-200 1200) $PN EP28
J 2
(-210 1210);
DISPLAY 0.680851 (-210 1210);
PAINT MONO (-210 1210);
FORCEPROP 0 LASTPIN (-200 1250) $PN EM26
J 2
(-210 1260);
DISPLAY 0.680851 (-210 1260);
PAINT MONO (-210 1260);
FORCEPROP 0 LASTPIN (-200 1300) $PN EL25
J 2
(-210 1310);
DISPLAY 0.680851 (-210 1310);
PAINT MONO (-210 1310);
FORCEPROP 0 LASTPIN (-200 1350) $PN EP26
J 2
(-210 1360);
DISPLAY 0.680851 (-210 1360);
PAINT MONO (-210 1360);
FORCEPROP 0 LASTPIN (-200 1400) $PN ER25
J 2
(-210 1410);
DISPLAY 0.680851 (-210 1410);
PAINT MONO (-210 1410);
FORCEPROP 0 LASTPIN (-200 1450) $PN EL23
J 2
(-210 1460);
DISPLAY 0.680851 (-210 1460);
PAINT MONO (-210 1460);
FORCEPROP 0 LASTPIN (-200 1500) $PN EM22
J 2
(-210 1510);
DISPLAY 0.680851 (-210 1510);
PAINT MONO (-210 1510);
FORCEPROP 0 LASTPIN (-200 1550) $PN ER23
J 2
(-210 1560);
DISPLAY 0.680851 (-210 1560);
PAINT MONO (-210 1560);
FORCEPROP 0 LASTPIN (-200 1600) $PN EP22
J 2
(-210 1610);
DISPLAY 0.680851 (-210 1610);
PAINT MONO (-210 1610);
FORCEPROP 0 LASTPIN (-200 1650) $PN EM20
J 2
(-210 1660);
DISPLAY 0.680851 (-210 1660);
PAINT MONO (-210 1660);
FORCEPROP 0 LASTPIN (-200 1700) $PN EL19
J 2
(-210 1710);
DISPLAY 0.680851 (-210 1710);
PAINT MONO (-210 1710);
FORCEPROP 0 LASTPIN (-200 1750) $PN EP20
J 2
(-210 1760);
DISPLAY 0.680851 (-210 1760);
PAINT MONO (-210 1760);
FORCEPROP 0 LASTPIN (-200 1800) $PN ER19
J 2
(-210 1810);
DISPLAY 0.680851 (-210 1810);
PAINT MONO (-210 1810);
FORCEPROP 0 LASTPIN (-200 1850) $PN EL17
J 2
(-210 1860);
DISPLAY 0.680851 (-210 1860);
PAINT MONO (-210 1860);
FORCEPROP 0 LASTPIN (-200 1900) $PN EM16
J 2
(-210 1910);
DISPLAY 0.680851 (-210 1910);
PAINT MONO (-210 1910);
FORCEPROP 0 LASTPIN (-200 1950) $PN ER17
J 2
(-210 1960);
DISPLAY 0.680851 (-210 1960);
PAINT MONO (-210 1960);
FORCEPROP 0 LASTPIN (-200 2000) $PN EP16
J 2
(-210 2010);
DISPLAY 0.680851 (-210 2010);
PAINT MONO (-210 2010);
FORCEPROP 0 LASTPIN (2250 1850) $PN EE27
J 0
(2260 1860);
DISPLAY 0.680851 (2260 1860);
PAINT MONO (2260 1860);
FORCEPROP 0 LASTPIN (2250 1900) $PN EK30
J 0
(2260 1910);
DISPLAY 0.680851 (2260 1910);
PAINT MONO (2260 1910);
FORCEPROP 0 LASTPIN (2250 1950) $PN EK24
J 0
(2260 1960);
DISPLAY 0.680851 (2260 1960);
PAINT MONO (2260 1960);
FORCEPROP 0 LASTPIN (2250 2000) $PN EK18
J 0
(2260 2010);
DISPLAY 0.680851 (2260 2010);
PAINT MONO (2260 2010);
FORCEPROP 0 LASTPIN (2250 2050) $PN ET36
J 0
(2260 2060);
DISPLAY 0.680851 (2260 2060);
PAINT MONO (2260 2060);
FORCEPROP 0 LASTPIN (2250 2100) $PN EJ27
J 0
(2260 2110);
DISPLAY 0.680851 (2260 2110);
PAINT MONO (2260 2110);
FORCEPROP 0 LASTPIN (2250 2150) $PN ET30
J 0
(2260 2160);
DISPLAY 0.680851 (2260 2160);
PAINT MONO (2260 2160);
FORCEPROP 0 LASTPIN (2250 2200) $PN ET24
J 0
(2260 2210);
DISPLAY 0.680851 (2260 2210);
PAINT MONO (2260 2210);
FORCEPROP 0 LASTPIN (2250 2250) $PN ET18
J 0
(2260 2260);
DISPLAY 0.680851 (2260 2260);
PAINT MONO (2260 2260);
FORCEPROP 0 LASTPIN (2250 2300) $PN EK36
J 0
(2260 2310);
DISPLAY 0.680851 (2260 2310);
PAINT MONO (2260 2310);
FORCEPROP 0 LASTPIN (2250 2400) $PN EC27
J 0
(2260 2410);
DISPLAY 0.680851 (2260 2410);
PAINT MONO (2260 2410);
FORCEPROP 0 LASTPIN (2250 2450) $PN EM30
J 0
(2260 2460);
DISPLAY 0.680851 (2260 2460);
PAINT MONO (2260 2460);
FORCEPROP 0 LASTPIN (2250 2500) $PN EM24
J 0
(2260 2510);
DISPLAY 0.680851 (2260 2510);
PAINT MONO (2260 2510);
FORCEPROP 0 LASTPIN (2250 2550) $PN EM18
J 0
(2260 2560);
DISPLAY 0.680851 (2260 2560);
PAINT MONO (2260 2560);
FORCEPROP 0 LASTPIN (2250 2600) $PN EP36
J 0
(2260 2610);
DISPLAY 0.680851 (2260 2610);
PAINT MONO (2260 2610);
FORCEPROP 0 LASTPIN (2250 2650) $PN EG27
J 0
(2260 2660);
DISPLAY 0.680851 (2260 2660);
PAINT MONO (2260 2660);
FORCEPROP 0 LASTPIN (2250 2700) $PN EP30
J 0
(2260 2710);
DISPLAY 0.680851 (2260 2710);
PAINT MONO (2260 2710);
FORCEPROP 0 LASTPIN (2250 2750) $PN EP24
J 0
(2260 2760);
DISPLAY 0.680851 (2260 2760);
PAINT MONO (2260 2760);
FORCEPROP 0 LASTPIN (2250 2800) $PN EP18
J 0
(2260 2810);
DISPLAY 0.680851 (2260 2810);
PAINT MONO (2260 2810);
FORCEPROP 0 LASTPIN (2250 2850) $PN EM36
J 0
(2260 2860);
DISPLAY 0.680851 (2260 2860);
PAINT MONO (2260 2860);
FORCEPROP 0 LASTPIN (-200 50) $PN EL35
J 2
(-210 60);
DISPLAY 0.680851 (-210 60);
PAINT MONO (-210 60);
FORCEPROP 0 LASTPIN (-200 100) $PN EM34
J 2
(-210 110);
DISPLAY 0.680851 (-210 110);
PAINT MONO (-210 110);
FORCEPROP 0 LASTPIN (-200 150) $PN ER35
J 2
(-210 160);
DISPLAY 0.680851 (-210 160);
PAINT MONO (-210 160);
FORCEPROP 0 LASTPIN (-200 200) $PN EP34
J 2
(-210 210);
DISPLAY 0.680851 (-210 210);
PAINT MONO (-210 210);
FORCEPROP 0 LASTPIN (-200 250) $PN EM38
J 2
(-210 260);
DISPLAY 0.680851 (-210 260);
PAINT MONO (-210 260);
FORCEPROP 0 LASTPIN (-200 300) $PN EL37
J 2
(-210 310);
DISPLAY 0.680851 (-210 310);
PAINT MONO (-210 310);
FORCEPROP 0 LASTPIN (-200 350) $PN EP38
J 2
(-210 360);
DISPLAY 0.680851 (-210 360);
PAINT MONO (-210 360);
FORCEPROP 0 LASTPIN (-200 400) $PN ER37
J 2
(-210 410);
DISPLAY 0.680851 (-210 410);
PAINT MONO (-210 410);
FORCEPROP 0 LASTPIN (2250 850) $PN EP42
J 0
(2260 860);
DISPLAY 0.680851 (2260 860);
PAINT MONO (2260 860);
FORCEPROP 0 LASTPIN (2250 550) $PN EP51
J 0
(2260 560);
DISPLAY 0.680851 (2260 560);
PAINT MONO (2260 560);
FORCEPROP 0 LASTPIN (2250 600) $PN ET51
J 0
(2260 610);
DISPLAY 0.680851 (2260 610);
PAINT MONO (2260 610);
FORCEPROP 0 LASTPIN (2250 650) $PN EM51
J 0
(2260 660);
DISPLAY 0.680851 (2260 660);
PAINT MONO (2260 660);
FORCEPROP 0 LASTPIN (2250 700) $PN EL50
J 0
(2260 710);
DISPLAY 0.680851 (2260 710);
PAINT MONO (2260 710);
FORCEPROP 0 LASTPIN (2250 250) $PN EP40
J 0
(2260 260);
DISPLAY 0.680851 (2260 260);
PAINT MONO (2260 260);
FORCEPROP 0 LASTPIN (2250 300) $PN ET40
J 0
(2260 310);
DISPLAY 0.680851 (2260 310);
PAINT MONO (2260 310);
FORCEPROP 0 LASTPIN (2250 350) $PN EM40
J 0
(2260 360);
DISPLAY 0.680851 (2260 360);
PAINT MONO (2260 360);
FORCEPROP 0 LASTPIN (2250 400) $PN EL41
J 0
(2260 410);
DISPLAY 0.680851 (2260 410);
PAINT MONO (2260 410);
FORCEPROP 2 LAST CDS_LIB pure_quanta
J 0
(1025 1900);
DISPLAY INVISIBLE (1025 1900);
FORCEPROP 1 LAST NEEDS_NO_SIZE TRUE
J 0
(1025 1900);
DISPLAY 0.723404 (1025 1900);
PAINT GREEN (1025 1900);
DISPLAY INVISIBLE (1025 1900);
FORCEPROP 1 LAST CDS_LMAN_SYM_OUTLINE -1100,2250,1050,-2250
J 0
(1025 1900);
DISPLAY 0.468085 (1025 1900);
PAINT GREEN (1025 1900);
DISPLAY INVISIBLE (1025 1900);
FORCEPROP 2 LAST CDS_LOCATION U2
J 0
(-75 4475);
DISPLAY 1.021277 (-75 4475);
DISPLAY INVISIBLE (-75 4475);
FORCEPROP 0 LAST $SEC 12
J 0
(-75 4475);
DISPLAY 0.680851 (-75 4475);
PAINT MONO (-75 4475);
DISPLAY INVISIBLE (-75 4475);
FORCEPROP 2 LAST CDS_SEC 12
J 0
(-75 4475);
DISPLAY 1.021277 (-75 4475);
DISPLAY INVISIBLE (-75 4475);
FORCEPROP 1 LAST PATH I169
J 0
(1025 1900);
DISPLAY 0.723404 (1025 1900);
PAINT GREEN (1025 1900);
DISPLAY INVISIBLE (1025 1900);
FORCEADD TAP..1
R 2
(-700 450);
FORCEPROP 3 LASTPIN (-650 450) SIG_NAME M_E_CPU0_SB_DQ<0>
J 0
(-640 460);
DISPLAY 0.659574 (-640 460);
PAINT MONO (-640 460);
DISPLAY INVISIBLE (-640 460);
FORCEPROP 1 LASTPIN (-650 450) BN 0
J 2
(-638 458);
DISPLAY 0.680851 (-638 458);
PAINT GREEN (-638 458);
FORCEPROP 2 LAST CDS_LIB standard
J 0
(-700 450);
DISPLAY INVISIBLE (-700 450);
FORCEPROP 1 LAST BODY_TYPE PLUMBING
J 2
(-700 500);
DISPLAY 0.872340 (-700 500);
PAINT GREEN (-700 500);
DISPLAY INVISIBLE (-700 500);
FORCEPROP 1 LAST HDL_TAP TRUE
J 2
(-1025 325);
DISPLAY 0.872340 (-1025 325);
DISPLAY INVISIBLE (-1025 325);
FORCEPROP 1 LAST PATH I17
J 2
(-698 450);
DISPLAY 0.872340 (-698 450);
PAINT GREEN (-698 450);
DISPLAY INVISIBLE (-698 450);
FORCEADD TAP..1
R 2
(-700 550);
FORCEPROP 3 LASTPIN (-650 550) SIG_NAME M_E_CPU0_SB_DQ<2>
J 0
(-640 560);
DISPLAY 0.659574 (-640 560);
PAINT MONO (-640 560);
DISPLAY INVISIBLE (-640 560);
FORCEPROP 1 LASTPIN (-650 550) BN 2
J 2
(-638 558);
DISPLAY 0.680851 (-638 558);
PAINT GREEN (-638 558);
FORCEPROP 2 LAST CDS_LIB standard
J 0
(-700 550);
DISPLAY INVISIBLE (-700 550);
FORCEPROP 1 LAST BODY_TYPE PLUMBING
J 2
(-700 600);
DISPLAY 0.872340 (-700 600);
PAINT GREEN (-700 600);
DISPLAY INVISIBLE (-700 600);
FORCEPROP 1 LAST HDL_TAP TRUE
J 2
(-1025 425);
DISPLAY 0.872340 (-1025 425);
DISPLAY INVISIBLE (-1025 425);
FORCEPROP 1 LAST PATH I18
J 2
(-698 550);
DISPLAY 0.872340 (-698 550);
PAINT GREEN (-698 550);
DISPLAY INVISIBLE (-698 550);
FORCEADD TAP..1
R 2
(-700 500);
FORCEPROP 3 LASTPIN (-650 500) SIG_NAME M_E_CPU0_SB_DQ<1>
J 0
(-640 510);
DISPLAY 0.659574 (-640 510);
PAINT MONO (-640 510);
DISPLAY INVISIBLE (-640 510);
FORCEPROP 1 LASTPIN (-650 500) BN 1
J 2
(-638 508);
DISPLAY 0.680851 (-638 508);
PAINT GREEN (-638 508);
FORCEPROP 2 LAST CDS_LIB standard
J 0
(-700 500);
DISPLAY INVISIBLE (-700 500);
FORCEPROP 1 LAST BODY_TYPE PLUMBING
J 2
(-700 550);
DISPLAY 0.872340 (-700 550);
PAINT GREEN (-700 550);
DISPLAY INVISIBLE (-700 550);
FORCEPROP 1 LAST HDL_TAP TRUE
J 2
(-1025 375);
DISPLAY 0.872340 (-1025 375);
DISPLAY INVISIBLE (-1025 375);
FORCEPROP 1 LAST PATH I19
J 2
(-698 500);
DISPLAY 0.872340 (-698 500);
PAINT GREEN (-698 500);
DISPLAY INVISIBLE (-698 500);
FORCEADD OFFPAGE..2
R 2
(-1725 -25);
FORCEPROP 2 LAST $XR1 91 
J 0
(-2069 -25);
DISPLAY 0.638298 (-2069 -25);
PAINT MONO (-2069 -25);
FORCEPROP 2 LAST $XR0 90 
J 0
(-1979 -25);
DISPLAY 0.638298 (-1979 -25);
PAINT MONO (-1979 -25);
FORCEPROP 2 LAST CDS_LIB standard
J 0
(-1725 -25);
PAINT MONO (-1725 -25);
DISPLAY INVISIBLE (-1725 -25);
FORCEPROP 1 LAST OFFPAGE TRUE
J 2
(-2050 -150);
DISPLAY 0.872340 (-2050 -150);
DISPLAY INVISIBLE (-2050 -150);
FORCEPROP 1 LAST COMMENT_BODY TRUE
J 2
(-1680 -120);
DISPLAY 0.872340 (-1680 -120);
PAINT GREEN (-1680 -120);
DISPLAY INVISIBLE (-1680 -120);
FORCEPROP 2 LAST PATH I2
J 0
(-1675 50);
DISPLAY 1.021277 (-1675 50);
DISPLAY INVISIBLE (-1675 50);
FORCEADD TAP..1
R 2
(-700 600);
FORCEPROP 3 LASTPIN (-650 600) SIG_NAME M_E_CPU0_SB_DQ<3>
J 0
(-640 610);
DISPLAY 0.659574 (-640 610);
PAINT MONO (-640 610);
DISPLAY INVISIBLE (-640 610);
FORCEPROP 1 LASTPIN (-650 600) BN 3
J 2
(-638 608);
DISPLAY 0.680851 (-638 608);
PAINT GREEN (-638 608);
FORCEPROP 2 LAST CDS_LIB standard
J 0
(-700 600);
DISPLAY INVISIBLE (-700 600);
FORCEPROP 1 LAST BODY_TYPE PLUMBING
J 2
(-700 650);
DISPLAY 0.872340 (-700 650);
PAINT GREEN (-700 650);
DISPLAY INVISIBLE (-700 650);
FORCEPROP 1 LAST HDL_TAP TRUE
J 2
(-1025 475);
DISPLAY 0.872340 (-1025 475);
DISPLAY INVISIBLE (-1025 475);
FORCEPROP 1 LAST PATH I20
J 2
(-698 600);
DISPLAY 0.872340 (-698 600);
PAINT GREEN (-698 600);
DISPLAY INVISIBLE (-698 600);
FORCEADD TAP..1
R 2
(-700 700);
FORCEPROP 3 LASTPIN (-650 700) SIG_NAME M_E_CPU0_SB_DQ<5>
J 0
(-640 710);
DISPLAY 0.659574 (-640 710);
PAINT MONO (-640 710);
DISPLAY INVISIBLE (-640 710);
FORCEPROP 1 LASTPIN (-650 700) BN 5
J 2
(-638 708);
DISPLAY 0.680851 (-638 708);
PAINT GREEN (-638 708);
FORCEPROP 2 LAST CDS_LIB standard
J 0
(-700 700);
DISPLAY INVISIBLE (-700 700);
FORCEPROP 1 LAST BODY_TYPE PLUMBING
J 2
(-700 750);
DISPLAY 0.872340 (-700 750);
PAINT GREEN (-700 750);
DISPLAY INVISIBLE (-700 750);
FORCEPROP 1 LAST HDL_TAP TRUE
J 2
(-1025 575);
DISPLAY 0.872340 (-1025 575);
DISPLAY INVISIBLE (-1025 575);
FORCEPROP 1 LAST PATH I21
J 2
(-698 700);
DISPLAY 0.872340 (-698 700);
PAINT GREEN (-698 700);
DISPLAY INVISIBLE (-698 700);
FORCEADD TAP..1
R 2
(-700 650);
FORCEPROP 3 LASTPIN (-650 650) SIG_NAME M_E_CPU0_SB_DQ<4>
J 0
(-640 660);
DISPLAY 0.659574 (-640 660);
PAINT MONO (-640 660);
DISPLAY INVISIBLE (-640 660);
FORCEPROP 1 LASTPIN (-650 650) BN 4
J 2
(-638 658);
DISPLAY 0.680851 (-638 658);
PAINT GREEN (-638 658);
FORCEPROP 2 LAST CDS_LIB standard
J 0
(-700 650);
DISPLAY INVISIBLE (-700 650);
FORCEPROP 1 LAST BODY_TYPE PLUMBING
J 2
(-700 700);
DISPLAY 0.872340 (-700 700);
PAINT GREEN (-700 700);
DISPLAY INVISIBLE (-700 700);
FORCEPROP 1 LAST HDL_TAP TRUE
J 2
(-1025 525);
DISPLAY 0.872340 (-1025 525);
DISPLAY INVISIBLE (-1025 525);
FORCEPROP 1 LAST PATH I22
J 2
(-698 650);
DISPLAY 0.872340 (-698 650);
PAINT GREEN (-698 650);
DISPLAY INVISIBLE (-698 650);
FORCEADD TAP..1
R 2
(-700 800);
FORCEPROP 3 LASTPIN (-650 800) SIG_NAME M_E_CPU0_SB_DQ<7>
J 0
(-640 810);
DISPLAY 0.659574 (-640 810);
PAINT MONO (-640 810);
DISPLAY INVISIBLE (-640 810);
FORCEPROP 1 LASTPIN (-650 800) BN 7
J 2
(-638 808);
DISPLAY 0.680851 (-638 808);
PAINT GREEN (-638 808);
FORCEPROP 2 LAST CDS_LIB standard
J 0
(-700 800);
DISPLAY INVISIBLE (-700 800);
FORCEPROP 1 LAST BODY_TYPE PLUMBING
J 2
(-700 850);
DISPLAY 0.872340 (-700 850);
PAINT GREEN (-700 850);
DISPLAY INVISIBLE (-700 850);
FORCEPROP 1 LAST HDL_TAP TRUE
J 2
(-1025 675);
DISPLAY 0.872340 (-1025 675);
DISPLAY INVISIBLE (-1025 675);
FORCEPROP 1 LAST PATH I23
J 2
(-698 800);
DISPLAY 0.872340 (-698 800);
PAINT GREEN (-698 800);
DISPLAY INVISIBLE (-698 800);
FORCEADD TAP..1
R 2
(-700 750);
FORCEPROP 3 LASTPIN (-650 750) SIG_NAME M_E_CPU0_SB_DQ<6>
J 0
(-640 760);
DISPLAY 0.659574 (-640 760);
PAINT MONO (-640 760);
DISPLAY INVISIBLE (-640 760);
FORCEPROP 1 LASTPIN (-650 750) BN 6
J 2
(-638 758);
DISPLAY 0.680851 (-638 758);
PAINT GREEN (-638 758);
FORCEPROP 2 LAST CDS_LIB standard
J 0
(-700 750);
DISPLAY INVISIBLE (-700 750);
FORCEPROP 1 LAST BODY_TYPE PLUMBING
J 2
(-700 800);
DISPLAY 0.872340 (-700 800);
PAINT GREEN (-700 800);
DISPLAY INVISIBLE (-700 800);
FORCEPROP 1 LAST HDL_TAP TRUE
J 2
(-1025 625);
DISPLAY 0.872340 (-1025 625);
DISPLAY INVISIBLE (-1025 625);
FORCEPROP 1 LAST PATH I24
J 2
(-698 750);
DISPLAY 0.872340 (-698 750);
PAINT GREEN (-698 750);
DISPLAY INVISIBLE (-698 750);
FORCEADD TAP..1
R 2
(-700 850);
FORCEPROP 3 LASTPIN (-650 850) SIG_NAME M_E_CPU0_SB_DQ<8>
J 0
(-640 860);
DISPLAY 0.659574 (-640 860);
PAINT MONO (-640 860);
DISPLAY INVISIBLE (-640 860);
FORCEPROP 1 LASTPIN (-650 850) BN 8
J 2
(-638 858);
DISPLAY 0.680851 (-638 858);
PAINT GREEN (-638 858);
FORCEPROP 2 LAST CDS_LIB standard
J 0
(-700 850);
DISPLAY INVISIBLE (-700 850);
FORCEPROP 1 LAST BODY_TYPE PLUMBING
J 2
(-700 900);
DISPLAY 0.872340 (-700 900);
PAINT GREEN (-700 900);
DISPLAY INVISIBLE (-700 900);
FORCEPROP 1 LAST HDL_TAP TRUE
J 2
(-1025 725);
DISPLAY 0.872340 (-1025 725);
DISPLAY INVISIBLE (-1025 725);
FORCEPROP 1 LAST PATH I25
J 2
(-698 850);
DISPLAY 0.872340 (-698 850);
PAINT GREEN (-698 850);
DISPLAY INVISIBLE (-698 850);
FORCEADD TAP..1
R 2
(-700 950);
FORCEPROP 3 LASTPIN (-650 950) SIG_NAME M_E_CPU0_SB_DQ<10>
J 0
(-640 960);
DISPLAY 0.659574 (-640 960);
PAINT MONO (-640 960);
DISPLAY INVISIBLE (-640 960);
FORCEPROP 1 LASTPIN (-650 950) BN 10
J 2
(-638 958);
DISPLAY 0.680851 (-638 958);
PAINT GREEN (-638 958);
FORCEPROP 2 LAST CDS_LIB standard
J 0
(-700 950);
DISPLAY INVISIBLE (-700 950);
FORCEPROP 1 LAST BODY_TYPE PLUMBING
J 2
(-700 1000);
DISPLAY 0.872340 (-700 1000);
PAINT GREEN (-700 1000);
DISPLAY INVISIBLE (-700 1000);
FORCEPROP 1 LAST HDL_TAP TRUE
J 2
(-1025 825);
DISPLAY 0.872340 (-1025 825);
DISPLAY INVISIBLE (-1025 825);
FORCEPROP 1 LAST PATH I26
J 2
(-698 950);
DISPLAY 0.872340 (-698 950);
PAINT GREEN (-698 950);
DISPLAY INVISIBLE (-698 950);
FORCEADD TAP..1
R 2
(-700 900);
FORCEPROP 3 LASTPIN (-650 900) SIG_NAME M_E_CPU0_SB_DQ<9>
J 0
(-640 910);
DISPLAY 0.659574 (-640 910);
PAINT MONO (-640 910);
DISPLAY INVISIBLE (-640 910);
FORCEPROP 1 LASTPIN (-650 900) BN 9
J 2
(-638 908);
DISPLAY 0.680851 (-638 908);
PAINT GREEN (-638 908);
FORCEPROP 2 LAST CDS_LIB standard
J 0
(-700 900);
DISPLAY INVISIBLE (-700 900);
FORCEPROP 1 LAST BODY_TYPE PLUMBING
J 2
(-700 950);
DISPLAY 0.872340 (-700 950);
PAINT GREEN (-700 950);
DISPLAY INVISIBLE (-700 950);
FORCEPROP 1 LAST HDL_TAP TRUE
J 2
(-1025 775);
DISPLAY 0.872340 (-1025 775);
DISPLAY INVISIBLE (-1025 775);
FORCEPROP 1 LAST PATH I27
J 2
(-698 900);
DISPLAY 0.872340 (-698 900);
PAINT GREEN (-698 900);
DISPLAY INVISIBLE (-698 900);
FORCEADD TAP..1
R 2
(-700 1050);
FORCEPROP 3 LASTPIN (-650 1050) SIG_NAME M_E_CPU0_SB_DQ<12>
J 0
(-640 1060);
DISPLAY 0.659574 (-640 1060);
PAINT MONO (-640 1060);
DISPLAY INVISIBLE (-640 1060);
FORCEPROP 1 LASTPIN (-650 1050) BN 12
J 2
(-638 1058);
DISPLAY 0.680851 (-638 1058);
PAINT GREEN (-638 1058);
FORCEPROP 2 LAST CDS_LIB standard
J 0
(-700 1050);
DISPLAY INVISIBLE (-700 1050);
FORCEPROP 1 LAST BODY_TYPE PLUMBING
J 2
(-700 1100);
DISPLAY 0.872340 (-700 1100);
PAINT GREEN (-700 1100);
DISPLAY INVISIBLE (-700 1100);
FORCEPROP 1 LAST HDL_TAP TRUE
J 2
(-1025 925);
DISPLAY 0.872340 (-1025 925);
DISPLAY INVISIBLE (-1025 925);
FORCEPROP 1 LAST PATH I28
J 2
(-698 1050);
DISPLAY 0.872340 (-698 1050);
PAINT GREEN (-698 1050);
DISPLAY INVISIBLE (-698 1050);
FORCEADD TAP..1
R 2
(-700 1000);
FORCEPROP 3 LASTPIN (-650 1000) SIG_NAME M_E_CPU0_SB_DQ<11>
J 0
(-640 1010);
DISPLAY 0.659574 (-640 1010);
PAINT MONO (-640 1010);
DISPLAY INVISIBLE (-640 1010);
FORCEPROP 1 LASTPIN (-650 1000) BN 11
J 2
(-638 1008);
DISPLAY 0.680851 (-638 1008);
PAINT GREEN (-638 1008);
FORCEPROP 2 LAST CDS_LIB standard
J 0
(-700 1000);
DISPLAY INVISIBLE (-700 1000);
FORCEPROP 1 LAST BODY_TYPE PLUMBING
J 2
(-700 1050);
DISPLAY 0.872340 (-700 1050);
PAINT GREEN (-700 1050);
DISPLAY INVISIBLE (-700 1050);
FORCEPROP 1 LAST HDL_TAP TRUE
J 2
(-1025 875);
DISPLAY 0.872340 (-1025 875);
DISPLAY INVISIBLE (-1025 875);
FORCEPROP 1 LAST PATH I29
J 2
(-698 1000);
DISPLAY 0.872340 (-698 1000);
PAINT GREEN (-698 1000);
DISPLAY INVISIBLE (-698 1000);
FORCEADD TAP..1
R 2
(-700 -200);
FORCEPROP 3 LASTPIN (-650 -200) SIG_NAME M_E_CPU0_CLK_DN<0>
J 0
(-640 -190);
DISPLAY 0.659574 (-640 -190);
PAINT MONO (-640 -190);
DISPLAY INVISIBLE (-640 -190);
FORCEPROP 1 LASTPIN (-650 -200) BN 0
J 2
(-638 -192);
DISPLAY 0.680851 (-638 -192);
PAINT GREEN (-638 -192);
FORCEPROP 2 LAST CDS_LIB standard
J 0
(-700 -200);
DISPLAY INVISIBLE (-700 -200);
FORCEPROP 1 LAST BODY_TYPE PLUMBING
J 2
(-700 -150);
DISPLAY 0.872340 (-700 -150);
PAINT GREEN (-700 -150);
DISPLAY INVISIBLE (-700 -150);
FORCEPROP 1 LAST HDL_TAP TRUE
J 2
(-1025 -325);
DISPLAY 0.872340 (-1025 -325);
DISPLAY INVISIBLE (-1025 -325);
FORCEPROP 1 LAST PATH I3
J 2
(-698 -200);
DISPLAY 0.872340 (-698 -200);
PAINT GREEN (-698 -200);
DISPLAY INVISIBLE (-698 -200);
FORCEADD TAP..1
R 2
(-700 1100);
FORCEPROP 3 LASTPIN (-650 1100) SIG_NAME M_E_CPU0_SB_DQ<13>
J 0
(-640 1110);
DISPLAY 0.659574 (-640 1110);
PAINT MONO (-640 1110);
DISPLAY INVISIBLE (-640 1110);
FORCEPROP 1 LASTPIN (-650 1100) BN 13
J 2
(-638 1108);
DISPLAY 0.680851 (-638 1108);
PAINT GREEN (-638 1108);
FORCEPROP 2 LAST CDS_LIB standard
J 0
(-700 1100);
DISPLAY INVISIBLE (-700 1100);
FORCEPROP 1 LAST BODY_TYPE PLUMBING
J 2
(-700 1150);
DISPLAY 0.872340 (-700 1150);
PAINT GREEN (-700 1150);
DISPLAY INVISIBLE (-700 1150);
FORCEPROP 1 LAST HDL_TAP TRUE
J 2
(-1025 975);
DISPLAY 0.872340 (-1025 975);
DISPLAY INVISIBLE (-1025 975);
FORCEPROP 1 LAST PATH I30
J 2
(-698 1100);
DISPLAY 0.872340 (-698 1100);
PAINT GREEN (-698 1100);
DISPLAY INVISIBLE (-698 1100);
FORCEADD TAP..1
R 2
(-700 1200);
FORCEPROP 3 LASTPIN (-650 1200) SIG_NAME M_E_CPU0_SB_DQ<15>
J 0
(-640 1210);
DISPLAY 0.659574 (-640 1210);
PAINT MONO (-640 1210);
DISPLAY INVISIBLE (-640 1210);
FORCEPROP 1 LASTPIN (-650 1200) BN 15
J 2
(-638 1208);
DISPLAY 0.680851 (-638 1208);
PAINT GREEN (-638 1208);
FORCEPROP 2 LAST CDS_LIB standard
J 0
(-700 1200);
DISPLAY INVISIBLE (-700 1200);
FORCEPROP 1 LAST BODY_TYPE PLUMBING
J 2
(-700 1250);
DISPLAY 0.872340 (-700 1250);
PAINT GREEN (-700 1250);
DISPLAY INVISIBLE (-700 1250);
FORCEPROP 1 LAST HDL_TAP TRUE
J 2
(-1025 1075);
DISPLAY 0.872340 (-1025 1075);
DISPLAY INVISIBLE (-1025 1075);
FORCEPROP 1 LAST PATH I31
J 2
(-698 1200);
DISPLAY 0.872340 (-698 1200);
PAINT GREEN (-698 1200);
DISPLAY INVISIBLE (-698 1200);
FORCEADD TAP..1
R 2
(-700 1150);
FORCEPROP 3 LASTPIN (-650 1150) SIG_NAME M_E_CPU0_SB_DQ<14>
J 0
(-640 1160);
DISPLAY 0.659574 (-640 1160);
PAINT MONO (-640 1160);
DISPLAY INVISIBLE (-640 1160);
FORCEPROP 1 LASTPIN (-650 1150) BN 14
J 2
(-638 1158);
DISPLAY 0.680851 (-638 1158);
PAINT GREEN (-638 1158);
FORCEPROP 2 LAST CDS_LIB standard
J 0
(-700 1150);
DISPLAY INVISIBLE (-700 1150);
FORCEPROP 1 LAST BODY_TYPE PLUMBING
J 2
(-700 1200);
DISPLAY 0.872340 (-700 1200);
PAINT GREEN (-700 1200);
DISPLAY INVISIBLE (-700 1200);
FORCEPROP 1 LAST HDL_TAP TRUE
J 2
(-1025 1025);
DISPLAY 0.872340 (-1025 1025);
DISPLAY INVISIBLE (-1025 1025);
FORCEPROP 1 LAST PATH I32
J 2
(-698 1150);
DISPLAY 0.872340 (-698 1150);
PAINT GREEN (-698 1150);
DISPLAY INVISIBLE (-698 1150);
FORCEADD TAP..1
R 2
(-700 1250);
FORCEPROP 3 LASTPIN (-650 1250) SIG_NAME M_E_CPU0_SB_DQ<16>
J 0
(-640 1260);
DISPLAY 0.659574 (-640 1260);
PAINT MONO (-640 1260);
DISPLAY INVISIBLE (-640 1260);
FORCEPROP 1 LASTPIN (-650 1250) BN 16
J 2
(-638 1258);
DISPLAY 0.680851 (-638 1258);
PAINT GREEN (-638 1258);
FORCEPROP 2 LAST CDS_LIB standard
J 0
(-700 1250);
DISPLAY INVISIBLE (-700 1250);
FORCEPROP 1 LAST BODY_TYPE PLUMBING
J 2
(-700 1300);
DISPLAY 0.872340 (-700 1300);
PAINT GREEN (-700 1300);
DISPLAY INVISIBLE (-700 1300);
FORCEPROP 1 LAST HDL_TAP TRUE
J 2
(-1025 1125);
DISPLAY 0.872340 (-1025 1125);
DISPLAY INVISIBLE (-1025 1125);
FORCEPROP 1 LAST PATH I33
J 2
(-698 1250);
DISPLAY 0.872340 (-698 1250);
PAINT GREEN (-698 1250);
DISPLAY INVISIBLE (-698 1250);
FORCEADD TAP..1
R 2
(-700 1350);
FORCEPROP 3 LASTPIN (-650 1350) SIG_NAME M_E_CPU0_SB_DQ<18>
J 0
(-640 1360);
DISPLAY 0.659574 (-640 1360);
PAINT MONO (-640 1360);
DISPLAY INVISIBLE (-640 1360);
FORCEPROP 1 LASTPIN (-650 1350) BN 18
J 2
(-638 1358);
DISPLAY 0.680851 (-638 1358);
PAINT GREEN (-638 1358);
FORCEPROP 2 LAST CDS_LIB standard
J 0
(-700 1350);
DISPLAY INVISIBLE (-700 1350);
FORCEPROP 1 LAST BODY_TYPE PLUMBING
J 2
(-700 1400);
DISPLAY 0.872340 (-700 1400);
PAINT GREEN (-700 1400);
DISPLAY INVISIBLE (-700 1400);
FORCEPROP 1 LAST HDL_TAP TRUE
J 2
(-1025 1225);
DISPLAY 0.872340 (-1025 1225);
DISPLAY INVISIBLE (-1025 1225);
FORCEPROP 1 LAST PATH I34
J 2
(-698 1350);
DISPLAY 0.872340 (-698 1350);
PAINT GREEN (-698 1350);
DISPLAY INVISIBLE (-698 1350);
FORCEADD TAP..1
R 2
(-700 1300);
FORCEPROP 3 LASTPIN (-650 1300) SIG_NAME M_E_CPU0_SB_DQ<17>
J 0
(-640 1310);
DISPLAY 0.659574 (-640 1310);
PAINT MONO (-640 1310);
DISPLAY INVISIBLE (-640 1310);
FORCEPROP 1 LASTPIN (-650 1300) BN 17
J 2
(-638 1308);
DISPLAY 0.680851 (-638 1308);
PAINT GREEN (-638 1308);
FORCEPROP 2 LAST CDS_LIB standard
J 0
(-700 1300);
DISPLAY INVISIBLE (-700 1300);
FORCEPROP 1 LAST BODY_TYPE PLUMBING
J 2
(-700 1350);
DISPLAY 0.872340 (-700 1350);
PAINT GREEN (-700 1350);
DISPLAY INVISIBLE (-700 1350);
FORCEPROP 1 LAST HDL_TAP TRUE
J 2
(-1025 1175);
DISPLAY 0.872340 (-1025 1175);
DISPLAY INVISIBLE (-1025 1175);
FORCEPROP 1 LAST PATH I35
J 2
(-698 1300);
DISPLAY 0.872340 (-698 1300);
PAINT GREEN (-698 1300);
DISPLAY INVISIBLE (-698 1300);
FORCEADD TAP..1
R 2
(-700 1450);
FORCEPROP 3 LASTPIN (-650 1450) SIG_NAME M_E_CPU0_SB_DQ<20>
J 0
(-640 1460);
DISPLAY 0.659574 (-640 1460);
PAINT MONO (-640 1460);
DISPLAY INVISIBLE (-640 1460);
FORCEPROP 1 LASTPIN (-650 1450) BN 20
J 2
(-638 1458);
DISPLAY 0.680851 (-638 1458);
PAINT GREEN (-638 1458);
FORCEPROP 2 LAST CDS_LIB standard
J 0
(-700 1450);
DISPLAY INVISIBLE (-700 1450);
FORCEPROP 1 LAST BODY_TYPE PLUMBING
J 2
(-700 1500);
DISPLAY 0.872340 (-700 1500);
PAINT GREEN (-700 1500);
DISPLAY INVISIBLE (-700 1500);
FORCEPROP 1 LAST HDL_TAP TRUE
J 2
(-1025 1325);
DISPLAY 0.872340 (-1025 1325);
DISPLAY INVISIBLE (-1025 1325);
FORCEPROP 1 LAST PATH I36
J 2
(-698 1450);
DISPLAY 0.872340 (-698 1450);
PAINT GREEN (-698 1450);
DISPLAY INVISIBLE (-698 1450);
FORCEADD TAP..1
R 2
(-700 1400);
FORCEPROP 3 LASTPIN (-650 1400) SIG_NAME M_E_CPU0_SB_DQ<19>
J 0
(-640 1410);
DISPLAY 0.659574 (-640 1410);
PAINT MONO (-640 1410);
DISPLAY INVISIBLE (-640 1410);
FORCEPROP 1 LASTPIN (-650 1400) BN 19
J 2
(-638 1408);
DISPLAY 0.680851 (-638 1408);
PAINT GREEN (-638 1408);
FORCEPROP 2 LAST CDS_LIB standard
J 0
(-700 1400);
DISPLAY INVISIBLE (-700 1400);
FORCEPROP 1 LAST BODY_TYPE PLUMBING
J 2
(-700 1450);
DISPLAY 0.872340 (-700 1450);
PAINT GREEN (-700 1450);
DISPLAY INVISIBLE (-700 1450);
FORCEPROP 1 LAST HDL_TAP TRUE
J 2
(-1025 1275);
DISPLAY 0.872340 (-1025 1275);
DISPLAY INVISIBLE (-1025 1275);
FORCEPROP 1 LAST PATH I37
J 2
(-698 1400);
DISPLAY 0.872340 (-698 1400);
PAINT GREEN (-698 1400);
DISPLAY INVISIBLE (-698 1400);
FORCEADD TAP..1
R 2
(-700 1500);
FORCEPROP 3 LASTPIN (-650 1500) SIG_NAME M_E_CPU0_SB_DQ<21>
J 0
(-640 1510);
DISPLAY 0.659574 (-640 1510);
PAINT MONO (-640 1510);
DISPLAY INVISIBLE (-640 1510);
FORCEPROP 1 LASTPIN (-650 1500) BN 21
J 2
(-638 1508);
DISPLAY 0.680851 (-638 1508);
PAINT GREEN (-638 1508);
FORCEPROP 2 LAST CDS_LIB standard
J 0
(-700 1500);
DISPLAY INVISIBLE (-700 1500);
FORCEPROP 1 LAST BODY_TYPE PLUMBING
J 2
(-700 1550);
DISPLAY 0.872340 (-700 1550);
PAINT GREEN (-700 1550);
DISPLAY INVISIBLE (-700 1550);
FORCEPROP 1 LAST HDL_TAP TRUE
J 2
(-1025 1375);
DISPLAY 0.872340 (-1025 1375);
DISPLAY INVISIBLE (-1025 1375);
FORCEPROP 1 LAST PATH I38
J 2
(-698 1500);
DISPLAY 0.872340 (-698 1500);
PAINT GREEN (-698 1500);
DISPLAY INVISIBLE (-698 1500);
FORCEADD TAP..1
R 2
(-700 1600);
FORCEPROP 3 LASTPIN (-650 1600) SIG_NAME M_E_CPU0_SB_DQ<23>
J 0
(-640 1610);
DISPLAY 0.659574 (-640 1610);
PAINT MONO (-640 1610);
DISPLAY INVISIBLE (-640 1610);
FORCEPROP 1 LASTPIN (-650 1600) BN 23
J 2
(-638 1608);
DISPLAY 0.680851 (-638 1608);
PAINT GREEN (-638 1608);
FORCEPROP 2 LAST CDS_LIB standard
J 0
(-700 1600);
DISPLAY INVISIBLE (-700 1600);
FORCEPROP 1 LAST BODY_TYPE PLUMBING
J 2
(-700 1650);
DISPLAY 0.872340 (-700 1650);
PAINT GREEN (-700 1650);
DISPLAY INVISIBLE (-700 1650);
FORCEPROP 1 LAST HDL_TAP TRUE
J 2
(-1025 1475);
DISPLAY 0.872340 (-1025 1475);
DISPLAY INVISIBLE (-1025 1475);
FORCEPROP 1 LAST PATH I39
J 2
(-698 1600);
DISPLAY 0.872340 (-698 1600);
PAINT GREEN (-698 1600);
DISPLAY INVISIBLE (-698 1600);
FORCEADD TAP..1
R 2
(-700 -150);
FORCEPROP 3 LASTPIN (-650 -150) SIG_NAME M_E_CPU0_CLK_DN<1>
J 0
(-640 -140);
DISPLAY 0.659574 (-640 -140);
PAINT MONO (-640 -140);
DISPLAY INVISIBLE (-640 -140);
FORCEPROP 1 LASTPIN (-650 -150) BN 1
J 2
(-638 -142);
DISPLAY 0.680851 (-638 -142);
PAINT GREEN (-638 -142);
FORCEPROP 2 LAST CDS_LIB standard
J 0
(-700 -150);
DISPLAY INVISIBLE (-700 -150);
FORCEPROP 1 LAST BODY_TYPE PLUMBING
J 2
(-700 -100);
DISPLAY 0.872340 (-700 -100);
PAINT GREEN (-700 -100);
DISPLAY INVISIBLE (-700 -100);
FORCEPROP 1 LAST HDL_TAP TRUE
J 2
(-1025 -275);
DISPLAY 0.872340 (-1025 -275);
DISPLAY INVISIBLE (-1025 -275);
FORCEPROP 1 LAST PATH I4
J 2
(-698 -150);
DISPLAY 0.872340 (-698 -150);
PAINT GREEN (-698 -150);
DISPLAY INVISIBLE (-698 -150);
FORCEADD TAP..1
R 2
(-700 1550);
FORCEPROP 3 LASTPIN (-650 1550) SIG_NAME M_E_CPU0_SB_DQ<22>
J 0
(-640 1560);
DISPLAY 0.659574 (-640 1560);
PAINT MONO (-640 1560);
DISPLAY INVISIBLE (-640 1560);
FORCEPROP 1 LASTPIN (-650 1550) BN 22
J 2
(-638 1558);
DISPLAY 0.680851 (-638 1558);
PAINT GREEN (-638 1558);
FORCEPROP 2 LAST CDS_LIB standard
J 0
(-700 1550);
DISPLAY INVISIBLE (-700 1550);
FORCEPROP 1 LAST BODY_TYPE PLUMBING
J 2
(-700 1600);
DISPLAY 0.872340 (-700 1600);
PAINT GREEN (-700 1600);
DISPLAY INVISIBLE (-700 1600);
FORCEPROP 1 LAST HDL_TAP TRUE
J 2
(-1025 1425);
DISPLAY 0.872340 (-1025 1425);
DISPLAY INVISIBLE (-1025 1425);
FORCEPROP 1 LAST PATH I40
J 2
(-698 1550);
DISPLAY 0.872340 (-698 1550);
PAINT GREEN (-698 1550);
DISPLAY INVISIBLE (-698 1550);
FORCEADD TAP..1
R 2
(-700 1700);
FORCEPROP 3 LASTPIN (-650 1700) SIG_NAME M_E_CPU0_SB_DQ<25>
J 0
(-640 1710);
DISPLAY 0.659574 (-640 1710);
PAINT MONO (-640 1710);
DISPLAY INVISIBLE (-640 1710);
FORCEPROP 1 LASTPIN (-650 1700) BN 25
J 2
(-638 1708);
DISPLAY 0.680851 (-638 1708);
PAINT GREEN (-638 1708);
FORCEPROP 2 LAST CDS_LIB standard
J 0
(-700 1700);
DISPLAY INVISIBLE (-700 1700);
FORCEPROP 1 LAST BODY_TYPE PLUMBING
J 2
(-700 1750);
DISPLAY 0.872340 (-700 1750);
PAINT GREEN (-700 1750);
DISPLAY INVISIBLE (-700 1750);
FORCEPROP 1 LAST HDL_TAP TRUE
J 2
(-1025 1575);
DISPLAY 0.872340 (-1025 1575);
DISPLAY INVISIBLE (-1025 1575);
FORCEPROP 1 LAST PATH I41
J 2
(-698 1700);
DISPLAY 0.872340 (-698 1700);
PAINT GREEN (-698 1700);
DISPLAY INVISIBLE (-698 1700);
FORCEADD TAP..1
R 2
(-700 1650);
FORCEPROP 3 LASTPIN (-650 1650) SIG_NAME M_E_CPU0_SB_DQ<24>
J 0
(-640 1660);
DISPLAY 0.659574 (-640 1660);
PAINT MONO (-640 1660);
DISPLAY INVISIBLE (-640 1660);
FORCEPROP 1 LASTPIN (-650 1650) BN 24
J 2
(-638 1658);
DISPLAY 0.680851 (-638 1658);
PAINT GREEN (-638 1658);
FORCEPROP 2 LAST CDS_LIB standard
J 0
(-700 1650);
DISPLAY INVISIBLE (-700 1650);
FORCEPROP 1 LAST BODY_TYPE PLUMBING
J 2
(-700 1700);
DISPLAY 0.872340 (-700 1700);
PAINT GREEN (-700 1700);
DISPLAY INVISIBLE (-700 1700);
FORCEPROP 1 LAST HDL_TAP TRUE
J 2
(-1025 1525);
DISPLAY 0.872340 (-1025 1525);
DISPLAY INVISIBLE (-1025 1525);
FORCEPROP 1 LAST PATH I42
J 2
(-698 1650);
DISPLAY 0.872340 (-698 1650);
PAINT GREEN (-698 1650);
DISPLAY INVISIBLE (-698 1650);
FORCEADD TAP..1
R 2
(-700 1750);
FORCEPROP 3 LASTPIN (-650 1750) SIG_NAME M_E_CPU0_SB_DQ<26>
J 0
(-640 1760);
DISPLAY 0.659574 (-640 1760);
PAINT MONO (-640 1760);
DISPLAY INVISIBLE (-640 1760);
FORCEPROP 1 LASTPIN (-650 1750) BN 26
J 2
(-638 1758);
DISPLAY 0.680851 (-638 1758);
PAINT GREEN (-638 1758);
FORCEPROP 2 LAST CDS_LIB standard
J 0
(-700 1750);
DISPLAY INVISIBLE (-700 1750);
FORCEPROP 1 LAST BODY_TYPE PLUMBING
J 2
(-700 1800);
DISPLAY 0.872340 (-700 1800);
PAINT GREEN (-700 1800);
DISPLAY INVISIBLE (-700 1800);
FORCEPROP 1 LAST HDL_TAP TRUE
J 2
(-1025 1625);
DISPLAY 0.872340 (-1025 1625);
DISPLAY INVISIBLE (-1025 1625);
FORCEPROP 1 LAST PATH I43
J 2
(-698 1750);
DISPLAY 0.872340 (-698 1750);
PAINT GREEN (-698 1750);
DISPLAY INVISIBLE (-698 1750);
FORCEADD TAP..1
R 2
(-700 1850);
FORCEPROP 3 LASTPIN (-650 1850) SIG_NAME M_E_CPU0_SB_DQ<28>
J 0
(-640 1860);
DISPLAY 0.659574 (-640 1860);
PAINT MONO (-640 1860);
DISPLAY INVISIBLE (-640 1860);
FORCEPROP 1 LASTPIN (-650 1850) BN 28
J 2
(-638 1858);
DISPLAY 0.680851 (-638 1858);
PAINT GREEN (-638 1858);
FORCEPROP 2 LAST CDS_LIB standard
J 0
(-700 1850);
DISPLAY INVISIBLE (-700 1850);
FORCEPROP 1 LAST BODY_TYPE PLUMBING
J 2
(-700 1900);
DISPLAY 0.872340 (-700 1900);
PAINT GREEN (-700 1900);
DISPLAY INVISIBLE (-700 1900);
FORCEPROP 1 LAST HDL_TAP TRUE
J 2
(-1025 1725);
DISPLAY 0.872340 (-1025 1725);
DISPLAY INVISIBLE (-1025 1725);
FORCEPROP 1 LAST PATH I44
J 2
(-698 1850);
DISPLAY 0.872340 (-698 1850);
PAINT GREEN (-698 1850);
DISPLAY INVISIBLE (-698 1850);
FORCEADD TAP..1
R 2
(-700 1800);
FORCEPROP 3 LASTPIN (-650 1800) SIG_NAME M_E_CPU0_SB_DQ<27>
J 0
(-640 1810);
DISPLAY 0.659574 (-640 1810);
PAINT MONO (-640 1810);
DISPLAY INVISIBLE (-640 1810);
FORCEPROP 1 LASTPIN (-650 1800) BN 27
J 2
(-638 1808);
DISPLAY 0.680851 (-638 1808);
PAINT GREEN (-638 1808);
FORCEPROP 2 LAST CDS_LIB standard
J 0
(-700 1800);
DISPLAY INVISIBLE (-700 1800);
FORCEPROP 1 LAST BODY_TYPE PLUMBING
J 2
(-700 1850);
DISPLAY 0.872340 (-700 1850);
PAINT GREEN (-700 1850);
DISPLAY INVISIBLE (-700 1850);
FORCEPROP 1 LAST HDL_TAP TRUE
J 2
(-1025 1675);
DISPLAY 0.872340 (-1025 1675);
DISPLAY INVISIBLE (-1025 1675);
FORCEPROP 1 LAST PATH I45
J 2
(-698 1800);
DISPLAY 0.872340 (-698 1800);
PAINT GREEN (-698 1800);
DISPLAY INVISIBLE (-698 1800);
FORCEADD TAP..1
R 2
(-700 1950);
FORCEPROP 3 LASTPIN (-650 1950) SIG_NAME M_E_CPU0_SB_DQ<30>
J 0
(-640 1960);
DISPLAY 0.659574 (-640 1960);
PAINT MONO (-640 1960);
DISPLAY INVISIBLE (-640 1960);
FORCEPROP 1 LASTPIN (-650 1950) BN 30
J 2
(-638 1958);
DISPLAY 0.680851 (-638 1958);
PAINT GREEN (-638 1958);
FORCEPROP 2 LAST CDS_LIB standard
J 0
(-700 1950);
DISPLAY INVISIBLE (-700 1950);
FORCEPROP 1 LAST BODY_TYPE PLUMBING
J 2
(-700 2000);
DISPLAY 0.872340 (-700 2000);
PAINT GREEN (-700 2000);
DISPLAY INVISIBLE (-700 2000);
FORCEPROP 1 LAST HDL_TAP TRUE
J 2
(-1025 1825);
DISPLAY 0.872340 (-1025 1825);
DISPLAY INVISIBLE (-1025 1825);
FORCEPROP 1 LAST PATH I46
J 2
(-698 1950);
DISPLAY 0.872340 (-698 1950);
PAINT GREEN (-698 1950);
DISPLAY INVISIBLE (-698 1950);
FORCEADD TAP..1
R 2
(-700 1900);
FORCEPROP 3 LASTPIN (-650 1900) SIG_NAME M_E_CPU0_SB_DQ<29>
J 0
(-640 1910);
DISPLAY 0.659574 (-640 1910);
PAINT MONO (-640 1910);
DISPLAY INVISIBLE (-640 1910);
FORCEPROP 1 LASTPIN (-650 1900) BN 29
J 2
(-638 1908);
DISPLAY 0.680851 (-638 1908);
PAINT GREEN (-638 1908);
FORCEPROP 2 LAST CDS_LIB standard
J 0
(-700 1900);
DISPLAY INVISIBLE (-700 1900);
FORCEPROP 1 LAST BODY_TYPE PLUMBING
J 2
(-700 1950);
DISPLAY 0.872340 (-700 1950);
PAINT GREEN (-700 1950);
DISPLAY INVISIBLE (-700 1950);
FORCEPROP 1 LAST HDL_TAP TRUE
J 2
(-1025 1775);
DISPLAY 0.872340 (-1025 1775);
DISPLAY INVISIBLE (-1025 1775);
FORCEPROP 1 LAST PATH I47
J 2
(-698 1900);
DISPLAY 0.872340 (-698 1900);
PAINT GREEN (-698 1900);
DISPLAY INVISIBLE (-698 1900);
FORCEADD TAP..1
R 2
(-700 2000);
FORCEPROP 3 LASTPIN (-650 2000) SIG_NAME M_E_CPU0_SB_DQ<31>
J 0
(-640 2010);
DISPLAY 0.659574 (-640 2010);
PAINT MONO (-640 2010);
DISPLAY INVISIBLE (-640 2010);
FORCEPROP 1 LASTPIN (-650 2000) BN 31
J 2
(-638 2008);
DISPLAY 0.680851 (-638 2008);
PAINT GREEN (-638 2008);
FORCEPROP 2 LAST CDS_LIB standard
J 0
(-700 2000);
DISPLAY INVISIBLE (-700 2000);
FORCEPROP 1 LAST BODY_TYPE PLUMBING
J 2
(-700 2050);
DISPLAY 0.872340 (-700 2050);
PAINT GREEN (-700 2050);
DISPLAY INVISIBLE (-700 2050);
FORCEPROP 1 LAST HDL_TAP TRUE
J 2
(-1025 1875);
DISPLAY 0.872340 (-1025 1875);
DISPLAY INVISIBLE (-1025 1875);
FORCEPROP 1 LAST PATH I48
J 2
(-698 2000);
DISPLAY 0.872340 (-698 2000);
PAINT GREEN (-698 2000);
DISPLAY INVISIBLE (-698 2000);
FORCEADD TAP..1
R 2
(-700 2100);
FORCEPROP 3 LASTPIN (-650 2100) SIG_NAME M_E_CPU0_SA_CB<1>
J 0
(-640 2110);
DISPLAY 0.659574 (-640 2110);
PAINT MONO (-640 2110);
DISPLAY INVISIBLE (-640 2110);
FORCEPROP 1 LASTPIN (-650 2100) BN 1
J 2
(-638 2108);
DISPLAY 0.680851 (-638 2108);
PAINT GREEN (-638 2108);
FORCEPROP 2 LAST CDS_LIB standard
J 0
(-700 2100);
DISPLAY INVISIBLE (-700 2100);
FORCEPROP 1 LAST BODY_TYPE PLUMBING
J 2
(-700 2150);
DISPLAY 0.872340 (-700 2150);
PAINT GREEN (-700 2150);
DISPLAY INVISIBLE (-700 2150);
FORCEPROP 1 LAST HDL_TAP TRUE
J 2
(-1025 1975);
DISPLAY 0.872340 (-1025 1975);
DISPLAY INVISIBLE (-1025 1975);
FORCEPROP 1 LAST PATH I49
J 2
(-698 2100);
DISPLAY 0.872340 (-698 2100);
PAINT GREEN (-698 2100);
DISPLAY INVISIBLE (-698 2100);
FORCEADD TAP..1
R 2
(-700 -50);
FORCEPROP 3 LASTPIN (-650 -50) SIG_NAME M_E_CPU0_CLK_DP<1>
J 0
(-640 -40);
DISPLAY 0.659574 (-640 -40);
PAINT MONO (-640 -40);
DISPLAY INVISIBLE (-640 -40);
FORCEPROP 1 LASTPIN (-650 -50) BN 1
J 2
(-638 -42);
DISPLAY 0.680851 (-638 -42);
PAINT GREEN (-638 -42);
FORCEPROP 2 LAST CDS_LIB standard
J 0
(-700 -50);
DISPLAY INVISIBLE (-700 -50);
FORCEPROP 1 LAST BODY_TYPE PLUMBING
J 2
(-700 0);
DISPLAY 0.872340 (-700 0);
PAINT GREEN (-700 0);
DISPLAY INVISIBLE (-700 0);
FORCEPROP 1 LAST HDL_TAP TRUE
J 2
(-1025 -175);
DISPLAY 0.872340 (-1025 -175);
DISPLAY INVISIBLE (-1025 -175);
FORCEPROP 1 LAST PATH I5
J 2
(-698 -50);
DISPLAY 0.872340 (-698 -50);
PAINT GREEN (-698 -50);
DISPLAY INVISIBLE (-698 -50);
FORCEADD TAP..1
R 2
(-700 2050);
FORCEPROP 3 LASTPIN (-650 2050) SIG_NAME M_E_CPU0_SA_CB<0>
J 0
(-640 2060);
DISPLAY 0.659574 (-640 2060);
PAINT MONO (-640 2060);
DISPLAY INVISIBLE (-640 2060);
FORCEPROP 1 LASTPIN (-650 2050) BN 0
J 2
(-638 2058);
DISPLAY 0.680851 (-638 2058);
PAINT GREEN (-638 2058);
FORCEPROP 2 LAST CDS_LIB standard
J 0
(-700 2050);
DISPLAY INVISIBLE (-700 2050);
FORCEPROP 1 LAST BODY_TYPE PLUMBING
J 2
(-700 2100);
DISPLAY 0.872340 (-700 2100);
PAINT GREEN (-700 2100);
DISPLAY INVISIBLE (-700 2100);
FORCEPROP 1 LAST HDL_TAP TRUE
J 2
(-1025 1925);
DISPLAY 0.872340 (-1025 1925);
DISPLAY INVISIBLE (-1025 1925);
FORCEPROP 1 LAST PATH I50
J 2
(-698 2050);
DISPLAY 0.872340 (-698 2050);
PAINT GREEN (-698 2050);
DISPLAY INVISIBLE (-698 2050);
FORCEADD OFFPAGE..3
R 2
(-1725 2425);
FORCEPROP 2 LAST $XR1 91 
J 0
(-2094 2425);
DISPLAY 0.638298 (-2094 2425);
PAINT MONO (-2094 2425);
FORCEPROP 2 LAST $XR0 90 
J 0
(-2004 2425);
DISPLAY 0.638298 (-2004 2425);
PAINT MONO (-2004 2425);
FORCEPROP 2 LAST CDS_LIB standard
J 0
(-1725 2425);
DISPLAY INVISIBLE (-1725 2425);
FORCEPROP 1 LAST OFFPAGE TRUE
J 2
(-2050 2300);
DISPLAY 0.872340 (-2050 2300);
DISPLAY INVISIBLE (-2050 2300);
FORCEPROP 1 LAST COMMENT_BODY TRUE
J 2
(-1675 2325);
DISPLAY 0.872340 (-1675 2325);
PAINT GREEN (-1675 2325);
DISPLAY INVISIBLE (-1675 2325);
FORCEPROP 2 LAST PATH I51
J 0
(-1675 2500);
DISPLAY 1.021277 (-1675 2500);
DISPLAY INVISIBLE (-1675 2500);
FORCEADD OFFPAGE..3
R 2
(-1725 4025);
FORCEPROP 2 LAST $XR1 91 
J 0
(-2094 4025);
DISPLAY 0.638298 (-2094 4025);
PAINT MONO (-2094 4025);
FORCEPROP 2 LAST $XR0 90 
J 0
(-2004 4025);
DISPLAY 0.638298 (-2004 4025);
PAINT MONO (-2004 4025);
FORCEPROP 2 LAST CDS_LIB standard
J 0
(-1725 4025);
DISPLAY INVISIBLE (-1725 4025);
FORCEPROP 1 LAST OFFPAGE TRUE
J 2
(-2050 3900);
DISPLAY 0.872340 (-2050 3900);
DISPLAY INVISIBLE (-2050 3900);
FORCEPROP 1 LAST COMMENT_BODY TRUE
J 2
(-1675 3925);
DISPLAY 0.872340 (-1675 3925);
PAINT GREEN (-1675 3925);
DISPLAY INVISIBLE (-1675 3925);
FORCEPROP 2 LAST PATH I52
J 0
(-1675 4100);
DISPLAY 1.021277 (-1675 4100);
DISPLAY INVISIBLE (-1675 4100);
FORCEADD TAP..1
R 2
(-700 2250);
FORCEPROP 3 LASTPIN (-650 2250) SIG_NAME M_E_CPU0_SA_CB<4>
J 0
(-640 2260);
DISPLAY 0.659574 (-640 2260);
PAINT MONO (-640 2260);
DISPLAY INVISIBLE (-640 2260);
FORCEPROP 1 LASTPIN (-650 2250) BN 4
J 2
(-638 2258);
DISPLAY 0.680851 (-638 2258);
PAINT GREEN (-638 2258);
FORCEPROP 2 LAST CDS_LIB standard
J 0
(-700 2250);
DISPLAY INVISIBLE (-700 2250);
FORCEPROP 1 LAST BODY_TYPE PLUMBING
J 2
(-700 2300);
DISPLAY 0.872340 (-700 2300);
PAINT GREEN (-700 2300);
DISPLAY INVISIBLE (-700 2300);
FORCEPROP 1 LAST HDL_TAP TRUE
J 2
(-1025 2125);
DISPLAY 0.872340 (-1025 2125);
DISPLAY INVISIBLE (-1025 2125);
FORCEPROP 1 LAST PATH I53
J 2
(-698 2250);
DISPLAY 0.872340 (-698 2250);
PAINT GREEN (-698 2250);
DISPLAY INVISIBLE (-698 2250);
FORCEADD TAP..1
R 2
(-700 2200);
FORCEPROP 3 LASTPIN (-650 2200) SIG_NAME M_E_CPU0_SA_CB<3>
J 0
(-640 2210);
DISPLAY 0.659574 (-640 2210);
PAINT MONO (-640 2210);
DISPLAY INVISIBLE (-640 2210);
FORCEPROP 1 LASTPIN (-650 2200) BN 3
J 2
(-638 2208);
DISPLAY 0.680851 (-638 2208);
PAINT GREEN (-638 2208);
FORCEPROP 2 LAST CDS_LIB standard
J 0
(-700 2200);
DISPLAY INVISIBLE (-700 2200);
FORCEPROP 1 LAST BODY_TYPE PLUMBING
J 2
(-700 2250);
DISPLAY 0.872340 (-700 2250);
PAINT GREEN (-700 2250);
DISPLAY INVISIBLE (-700 2250);
FORCEPROP 1 LAST HDL_TAP TRUE
J 2
(-1025 2075);
DISPLAY 0.872340 (-1025 2075);
DISPLAY INVISIBLE (-1025 2075);
FORCEPROP 1 LAST PATH I54
J 2
(-698 2200);
DISPLAY 0.872340 (-698 2200);
PAINT GREEN (-698 2200);
DISPLAY INVISIBLE (-698 2200);
FORCEADD TAP..1
R 2
(-700 2150);
FORCEPROP 3 LASTPIN (-650 2150) SIG_NAME M_E_CPU0_SA_CB<2>
J 0
(-640 2160);
DISPLAY 0.659574 (-640 2160);
PAINT MONO (-640 2160);
DISPLAY INVISIBLE (-640 2160);
FORCEPROP 1 LASTPIN (-650 2150) BN 2
J 2
(-638 2158);
DISPLAY 0.680851 (-638 2158);
PAINT GREEN (-638 2158);
FORCEPROP 2 LAST CDS_LIB standard
J 0
(-700 2150);
DISPLAY INVISIBLE (-700 2150);
FORCEPROP 1 LAST BODY_TYPE PLUMBING
J 2
(-700 2200);
DISPLAY 0.872340 (-700 2200);
PAINT GREEN (-700 2200);
DISPLAY INVISIBLE (-700 2200);
FORCEPROP 1 LAST HDL_TAP TRUE
J 2
(-1025 2025);
DISPLAY 0.872340 (-1025 2025);
DISPLAY INVISIBLE (-1025 2025);
FORCEPROP 1 LAST PATH I55
J 2
(-698 2150);
DISPLAY 0.872340 (-698 2150);
PAINT GREEN (-698 2150);
DISPLAY INVISIBLE (-698 2150);
FORCEADD TAP..1
R 2
(-700 2350);
FORCEPROP 3 LASTPIN (-650 2350) SIG_NAME M_E_CPU0_SA_CB<6>
J 0
(-640 2360);
DISPLAY 0.659574 (-640 2360);
PAINT MONO (-640 2360);
DISPLAY INVISIBLE (-640 2360);
FORCEPROP 1 LASTPIN (-650 2350) BN 6
J 2
(-638 2358);
DISPLAY 0.680851 (-638 2358);
PAINT GREEN (-638 2358);
FORCEPROP 2 LAST CDS_LIB standard
J 0
(-700 2350);
DISPLAY INVISIBLE (-700 2350);
FORCEPROP 1 LAST BODY_TYPE PLUMBING
J 2
(-700 2400);
DISPLAY 0.872340 (-700 2400);
PAINT GREEN (-700 2400);
DISPLAY INVISIBLE (-700 2400);
FORCEPROP 1 LAST HDL_TAP TRUE
J 2
(-1025 2225);
DISPLAY 0.872340 (-1025 2225);
DISPLAY INVISIBLE (-1025 2225);
FORCEPROP 1 LAST PATH I56
J 2
(-698 2350);
DISPLAY 0.872340 (-698 2350);
PAINT GREEN (-698 2350);
DISPLAY INVISIBLE (-698 2350);
FORCEADD TAP..1
R 2
(-700 2300);
FORCEPROP 3 LASTPIN (-650 2300) SIG_NAME M_E_CPU0_SA_CB<5>
J 0
(-640 2310);
DISPLAY 0.659574 (-640 2310);
PAINT MONO (-640 2310);
DISPLAY INVISIBLE (-640 2310);
FORCEPROP 1 LASTPIN (-650 2300) BN 5
J 2
(-638 2308);
DISPLAY 0.680851 (-638 2308);
PAINT GREEN (-638 2308);
FORCEPROP 2 LAST CDS_LIB standard
J 0
(-700 2300);
DISPLAY INVISIBLE (-700 2300);
FORCEPROP 1 LAST BODY_TYPE PLUMBING
J 2
(-700 2350);
DISPLAY 0.872340 (-700 2350);
PAINT GREEN (-700 2350);
DISPLAY INVISIBLE (-700 2350);
FORCEPROP 1 LAST HDL_TAP TRUE
J 2
(-1025 2175);
DISPLAY 0.872340 (-1025 2175);
DISPLAY INVISIBLE (-1025 2175);
FORCEPROP 1 LAST PATH I57
J 2
(-698 2300);
DISPLAY 0.872340 (-698 2300);
PAINT GREEN (-698 2300);
DISPLAY INVISIBLE (-698 2300);
FORCEADD TAP..1
R 2
(-700 2400);
FORCEPROP 3 LASTPIN (-650 2400) SIG_NAME M_E_CPU0_SA_CB<7>
J 0
(-640 2410);
DISPLAY 0.659574 (-640 2410);
PAINT MONO (-640 2410);
DISPLAY INVISIBLE (-640 2410);
FORCEPROP 1 LASTPIN (-650 2400) BN 7
J 2
(-638 2408);
DISPLAY 0.680851 (-638 2408);
PAINT GREEN (-638 2408);
FORCEPROP 2 LAST CDS_LIB standard
J 0
(-700 2400);
DISPLAY INVISIBLE (-700 2400);
FORCEPROP 1 LAST BODY_TYPE PLUMBING
J 2
(-700 2450);
DISPLAY 0.872340 (-700 2450);
PAINT GREEN (-700 2450);
DISPLAY INVISIBLE (-700 2450);
FORCEPROP 1 LAST HDL_TAP TRUE
J 2
(-1025 2275);
DISPLAY 0.872340 (-1025 2275);
DISPLAY INVISIBLE (-1025 2275);
FORCEPROP 1 LAST PATH I58
J 2
(-698 2400);
DISPLAY 0.872340 (-698 2400);
PAINT GREEN (-698 2400);
DISPLAY INVISIBLE (-698 2400);
FORCEADD TAP..1
R 2
(-700 2450);
FORCEPROP 3 LASTPIN (-650 2450) SIG_NAME M_E_CPU0_SA_DQ<0>
J 0
(-640 2460);
DISPLAY 0.659574 (-640 2460);
PAINT MONO (-640 2460);
DISPLAY INVISIBLE (-640 2460);
FORCEPROP 1 LASTPIN (-650 2450) BN 0
J 2
(-638 2458);
DISPLAY 0.680851 (-638 2458);
PAINT GREEN (-638 2458);
FORCEPROP 2 LAST CDS_LIB standard
J 0
(-700 2450);
DISPLAY INVISIBLE (-700 2450);
FORCEPROP 1 LAST BODY_TYPE PLUMBING
J 2
(-700 2500);
DISPLAY 0.872340 (-700 2500);
PAINT GREEN (-700 2500);
DISPLAY INVISIBLE (-700 2500);
FORCEPROP 1 LAST HDL_TAP TRUE
J 2
(-1025 2325);
DISPLAY 0.872340 (-1025 2325);
DISPLAY INVISIBLE (-1025 2325);
FORCEPROP 1 LAST PATH I59
J 2
(-698 2450);
DISPLAY 0.872340 (-698 2450);
PAINT GREEN (-698 2450);
DISPLAY INVISIBLE (-698 2450);
FORCEADD TAP..1
R 2
(-700 -100);
FORCEPROP 3 LASTPIN (-650 -100) SIG_NAME M_E_CPU0_CLK_DP<0>
J 0
(-640 -90);
DISPLAY 0.659574 (-640 -90);
PAINT MONO (-640 -90);
DISPLAY INVISIBLE (-640 -90);
FORCEPROP 1 LASTPIN (-650 -100) BN 0
J 2
(-638 -92);
DISPLAY 0.680851 (-638 -92);
PAINT GREEN (-638 -92);
FORCEPROP 2 LAST CDS_LIB standard
J 0
(-700 -100);
DISPLAY INVISIBLE (-700 -100);
FORCEPROP 1 LAST BODY_TYPE PLUMBING
J 2
(-700 -50);
DISPLAY 0.872340 (-700 -50);
PAINT GREEN (-700 -50);
DISPLAY INVISIBLE (-700 -50);
FORCEPROP 1 LAST HDL_TAP TRUE
J 2
(-1025 -225);
DISPLAY 0.872340 (-1025 -225);
DISPLAY INVISIBLE (-1025 -225);
FORCEPROP 1 LAST PATH I6
J 2
(-698 -100);
DISPLAY 0.872340 (-698 -100);
PAINT GREEN (-698 -100);
DISPLAY INVISIBLE (-698 -100);
FORCEADD TAP..1
R 2
(-700 2500);
FORCEPROP 3 LASTPIN (-650 2500) SIG_NAME M_E_CPU0_SA_DQ<1>
J 0
(-640 2510);
DISPLAY 0.659574 (-640 2510);
PAINT MONO (-640 2510);
DISPLAY INVISIBLE (-640 2510);
FORCEPROP 1 LASTPIN (-650 2500) BN 1
J 2
(-638 2508);
DISPLAY 0.680851 (-638 2508);
PAINT GREEN (-638 2508);
FORCEPROP 2 LAST CDS_LIB standard
J 0
(-700 2500);
DISPLAY INVISIBLE (-700 2500);
FORCEPROP 1 LAST BODY_TYPE PLUMBING
J 2
(-700 2550);
DISPLAY 0.872340 (-700 2550);
PAINT GREEN (-700 2550);
DISPLAY INVISIBLE (-700 2550);
FORCEPROP 1 LAST HDL_TAP TRUE
J 2
(-1025 2375);
DISPLAY 0.872340 (-1025 2375);
DISPLAY INVISIBLE (-1025 2375);
FORCEPROP 1 LAST PATH I60
J 2
(-698 2500);
DISPLAY 0.872340 (-698 2500);
PAINT GREEN (-698 2500);
DISPLAY INVISIBLE (-698 2500);
FORCEADD TAP..1
R 2
(-700 2600);
FORCEPROP 3 LASTPIN (-650 2600) SIG_NAME M_E_CPU0_SA_DQ<3>
J 0
(-640 2610);
DISPLAY 0.659574 (-640 2610);
PAINT MONO (-640 2610);
DISPLAY INVISIBLE (-640 2610);
FORCEPROP 1 LASTPIN (-650 2600) BN 3
J 2
(-638 2608);
DISPLAY 0.680851 (-638 2608);
PAINT GREEN (-638 2608);
FORCEPROP 2 LAST CDS_LIB standard
J 0
(-700 2600);
DISPLAY INVISIBLE (-700 2600);
FORCEPROP 1 LAST BODY_TYPE PLUMBING
J 2
(-700 2650);
DISPLAY 0.872340 (-700 2650);
PAINT GREEN (-700 2650);
DISPLAY INVISIBLE (-700 2650);
FORCEPROP 1 LAST HDL_TAP TRUE
J 2
(-1025 2475);
DISPLAY 0.872340 (-1025 2475);
DISPLAY INVISIBLE (-1025 2475);
FORCEPROP 1 LAST PATH I61
J 2
(-698 2600);
DISPLAY 0.872340 (-698 2600);
PAINT GREEN (-698 2600);
DISPLAY INVISIBLE (-698 2600);
FORCEADD TAP..1
R 2
(-700 2550);
FORCEPROP 3 LASTPIN (-650 2550) SIG_NAME M_E_CPU0_SA_DQ<2>
J 0
(-640 2560);
DISPLAY 0.659574 (-640 2560);
PAINT MONO (-640 2560);
DISPLAY INVISIBLE (-640 2560);
FORCEPROP 1 LASTPIN (-650 2550) BN 2
J 2
(-638 2558);
DISPLAY 0.680851 (-638 2558);
PAINT GREEN (-638 2558);
FORCEPROP 2 LAST CDS_LIB standard
J 0
(-700 2550);
DISPLAY INVISIBLE (-700 2550);
FORCEPROP 1 LAST BODY_TYPE PLUMBING
J 2
(-700 2600);
DISPLAY 0.872340 (-700 2600);
PAINT GREEN (-700 2600);
DISPLAY INVISIBLE (-700 2600);
FORCEPROP 1 LAST HDL_TAP TRUE
J 2
(-1025 2425);
DISPLAY 0.872340 (-1025 2425);
DISPLAY INVISIBLE (-1025 2425);
FORCEPROP 1 LAST PATH I62
J 2
(-698 2550);
DISPLAY 0.872340 (-698 2550);
PAINT GREEN (-698 2550);
DISPLAY INVISIBLE (-698 2550);
FORCEADD TAP..1
R 2
(-700 2650);
FORCEPROP 3 LASTPIN (-650 2650) SIG_NAME M_E_CPU0_SA_DQ<4>
J 0
(-640 2660);
DISPLAY 0.659574 (-640 2660);
PAINT MONO (-640 2660);
DISPLAY INVISIBLE (-640 2660);
FORCEPROP 1 LASTPIN (-650 2650) BN 4
J 2
(-638 2658);
DISPLAY 0.680851 (-638 2658);
PAINT GREEN (-638 2658);
FORCEPROP 2 LAST CDS_LIB standard
J 0
(-700 2650);
DISPLAY INVISIBLE (-700 2650);
FORCEPROP 1 LAST BODY_TYPE PLUMBING
J 2
(-700 2700);
DISPLAY 0.872340 (-700 2700);
PAINT GREEN (-700 2700);
DISPLAY INVISIBLE (-700 2700);
FORCEPROP 1 LAST HDL_TAP TRUE
J 2
(-1025 2525);
DISPLAY 0.872340 (-1025 2525);
DISPLAY INVISIBLE (-1025 2525);
FORCEPROP 1 LAST PATH I63
J 2
(-698 2650);
DISPLAY 0.872340 (-698 2650);
PAINT GREEN (-698 2650);
DISPLAY INVISIBLE (-698 2650);
FORCEADD TAP..1
R 2
(-700 2750);
FORCEPROP 3 LASTPIN (-650 2750) SIG_NAME M_E_CPU0_SA_DQ<6>
J 0
(-640 2760);
DISPLAY 0.659574 (-640 2760);
PAINT MONO (-640 2760);
DISPLAY INVISIBLE (-640 2760);
FORCEPROP 1 LASTPIN (-650 2750) BN 6
J 2
(-638 2758);
DISPLAY 0.680851 (-638 2758);
PAINT GREEN (-638 2758);
FORCEPROP 2 LAST CDS_LIB standard
J 0
(-700 2750);
DISPLAY INVISIBLE (-700 2750);
FORCEPROP 1 LAST BODY_TYPE PLUMBING
J 2
(-700 2800);
DISPLAY 0.872340 (-700 2800);
PAINT GREEN (-700 2800);
DISPLAY INVISIBLE (-700 2800);
FORCEPROP 1 LAST HDL_TAP TRUE
J 2
(-1025 2625);
DISPLAY 0.872340 (-1025 2625);
DISPLAY INVISIBLE (-1025 2625);
FORCEPROP 1 LAST PATH I64
J 2
(-698 2750);
DISPLAY 0.872340 (-698 2750);
PAINT GREEN (-698 2750);
DISPLAY INVISIBLE (-698 2750);
FORCEADD TAP..1
R 2
(-700 2700);
FORCEPROP 3 LASTPIN (-650 2700) SIG_NAME M_E_CPU0_SA_DQ<5>
J 0
(-640 2710);
DISPLAY 0.659574 (-640 2710);
PAINT MONO (-640 2710);
DISPLAY INVISIBLE (-640 2710);
FORCEPROP 1 LASTPIN (-650 2700) BN 5
J 2
(-638 2708);
DISPLAY 0.680851 (-638 2708);
PAINT GREEN (-638 2708);
FORCEPROP 2 LAST CDS_LIB standard
J 0
(-700 2700);
DISPLAY INVISIBLE (-700 2700);
FORCEPROP 1 LAST BODY_TYPE PLUMBING
J 2
(-700 2750);
DISPLAY 0.872340 (-700 2750);
PAINT GREEN (-700 2750);
DISPLAY INVISIBLE (-700 2750);
FORCEPROP 1 LAST HDL_TAP TRUE
J 2
(-1025 2575);
DISPLAY 0.872340 (-1025 2575);
DISPLAY INVISIBLE (-1025 2575);
FORCEPROP 1 LAST PATH I65
J 2
(-698 2700);
DISPLAY 0.872340 (-698 2700);
PAINT GREEN (-698 2700);
DISPLAY INVISIBLE (-698 2700);
FORCEADD TAP..1
R 2
(-700 2850);
FORCEPROP 3 LASTPIN (-650 2850) SIG_NAME M_E_CPU0_SA_DQ<8>
J 0
(-640 2860);
DISPLAY 0.659574 (-640 2860);
PAINT MONO (-640 2860);
DISPLAY INVISIBLE (-640 2860);
FORCEPROP 1 LASTPIN (-650 2850) BN 8
J 2
(-638 2858);
DISPLAY 0.680851 (-638 2858);
PAINT GREEN (-638 2858);
FORCEPROP 2 LAST CDS_LIB standard
J 0
(-700 2850);
DISPLAY INVISIBLE (-700 2850);
FORCEPROP 1 LAST BODY_TYPE PLUMBING
J 2
(-700 2900);
DISPLAY 0.872340 (-700 2900);
PAINT GREEN (-700 2900);
DISPLAY INVISIBLE (-700 2900);
FORCEPROP 1 LAST HDL_TAP TRUE
J 2
(-1025 2725);
DISPLAY 0.872340 (-1025 2725);
DISPLAY INVISIBLE (-1025 2725);
FORCEPROP 1 LAST PATH I66
J 2
(-698 2850);
DISPLAY 0.872340 (-698 2850);
PAINT GREEN (-698 2850);
DISPLAY INVISIBLE (-698 2850);
FORCEADD TAP..1
R 2
(-700 2800);
FORCEPROP 3 LASTPIN (-650 2800) SIG_NAME M_E_CPU0_SA_DQ<7>
J 0
(-640 2810);
DISPLAY 0.659574 (-640 2810);
PAINT MONO (-640 2810);
DISPLAY INVISIBLE (-640 2810);
FORCEPROP 1 LASTPIN (-650 2800) BN 7
J 2
(-638 2808);
DISPLAY 0.680851 (-638 2808);
PAINT GREEN (-638 2808);
FORCEPROP 2 LAST CDS_LIB standard
J 0
(-700 2800);
DISPLAY INVISIBLE (-700 2800);
FORCEPROP 1 LAST BODY_TYPE PLUMBING
J 2
(-700 2850);
DISPLAY 0.872340 (-700 2850);
PAINT GREEN (-700 2850);
DISPLAY INVISIBLE (-700 2850);
FORCEPROP 1 LAST HDL_TAP TRUE
J 2
(-1025 2675);
DISPLAY 0.872340 (-1025 2675);
DISPLAY INVISIBLE (-1025 2675);
FORCEPROP 1 LAST PATH I67
J 2
(-698 2800);
DISPLAY 0.872340 (-698 2800);
PAINT GREEN (-698 2800);
DISPLAY INVISIBLE (-698 2800);
FORCEADD TAP..1
R 2
(-700 2900);
FORCEPROP 3 LASTPIN (-650 2900) SIG_NAME M_E_CPU0_SA_DQ<9>
J 0
(-640 2910);
DISPLAY 0.659574 (-640 2910);
PAINT MONO (-640 2910);
DISPLAY INVISIBLE (-640 2910);
FORCEPROP 1 LASTPIN (-650 2900) BN 9
J 2
(-638 2908);
DISPLAY 0.680851 (-638 2908);
PAINT GREEN (-638 2908);
FORCEPROP 2 LAST CDS_LIB standard
J 0
(-700 2900);
DISPLAY INVISIBLE (-700 2900);
FORCEPROP 1 LAST BODY_TYPE PLUMBING
J 2
(-700 2950);
DISPLAY 0.872340 (-700 2950);
PAINT GREEN (-700 2950);
DISPLAY INVISIBLE (-700 2950);
FORCEPROP 1 LAST HDL_TAP TRUE
J 2
(-1025 2775);
DISPLAY 0.872340 (-1025 2775);
DISPLAY INVISIBLE (-1025 2775);
FORCEPROP 1 LAST PATH I68
J 2
(-698 2900);
DISPLAY 0.872340 (-698 2900);
PAINT GREEN (-698 2900);
DISPLAY INVISIBLE (-698 2900);
FORCEADD TAP..1
R 2
(-700 3000);
FORCEPROP 3 LASTPIN (-650 3000) SIG_NAME M_E_CPU0_SA_DQ<11>
J 0
(-640 3010);
DISPLAY 0.659574 (-640 3010);
PAINT MONO (-640 3010);
DISPLAY INVISIBLE (-640 3010);
FORCEPROP 1 LASTPIN (-650 3000) BN 11
J 2
(-638 3008);
DISPLAY 0.680851 (-638 3008);
PAINT GREEN (-638 3008);
FORCEPROP 2 LAST CDS_LIB standard
J 0
(-700 3000);
DISPLAY INVISIBLE (-700 3000);
FORCEPROP 1 LAST BODY_TYPE PLUMBING
J 2
(-700 3050);
DISPLAY 0.872340 (-700 3050);
PAINT GREEN (-700 3050);
DISPLAY INVISIBLE (-700 3050);
FORCEPROP 1 LAST HDL_TAP TRUE
J 2
(-1025 2875);
DISPLAY 0.872340 (-1025 2875);
DISPLAY INVISIBLE (-1025 2875);
FORCEPROP 1 LAST PATH I69
J 2
(-698 3000);
DISPLAY 0.872340 (-698 3000);
PAINT GREEN (-698 3000);
DISPLAY INVISIBLE (-698 3000);
FORCEADD TAP..1
R 2
(-700 50);
FORCEPROP 3 LASTPIN (-650 50) SIG_NAME M_E_CPU0_SB_CB<0>
J 0
(-640 60);
DISPLAY 0.659574 (-640 60);
PAINT MONO (-640 60);
DISPLAY INVISIBLE (-640 60);
FORCEPROP 1 LASTPIN (-650 50) BN 0
J 2
(-638 58);
DISPLAY 0.680851 (-638 58);
PAINT GREEN (-638 58);
FORCEPROP 2 LAST CDS_LIB standard
J 0
(-700 50);
DISPLAY INVISIBLE (-700 50);
FORCEPROP 1 LAST BODY_TYPE PLUMBING
J 2
(-700 100);
DISPLAY 0.872340 (-700 100);
PAINT GREEN (-700 100);
DISPLAY INVISIBLE (-700 100);
FORCEPROP 1 LAST HDL_TAP TRUE
J 2
(-1025 -75);
DISPLAY 0.872340 (-1025 -75);
DISPLAY INVISIBLE (-1025 -75);
FORCEPROP 1 LAST PATH I7
J 2
(-698 50);
DISPLAY 0.872340 (-698 50);
PAINT GREEN (-698 50);
DISPLAY INVISIBLE (-698 50);
FORCEADD TAP..1
R 2
(-700 2950);
FORCEPROP 3 LASTPIN (-650 2950) SIG_NAME M_E_CPU0_SA_DQ<10>
J 0
(-640 2960);
DISPLAY 0.659574 (-640 2960);
PAINT MONO (-640 2960);
DISPLAY INVISIBLE (-640 2960);
FORCEPROP 1 LASTPIN (-650 2950) BN 10
J 2
(-638 2958);
DISPLAY 0.680851 (-638 2958);
PAINT GREEN (-638 2958);
FORCEPROP 2 LAST CDS_LIB standard
J 0
(-700 2950);
DISPLAY INVISIBLE (-700 2950);
FORCEPROP 1 LAST BODY_TYPE PLUMBING
J 2
(-700 3000);
DISPLAY 0.872340 (-700 3000);
PAINT GREEN (-700 3000);
DISPLAY INVISIBLE (-700 3000);
FORCEPROP 1 LAST HDL_TAP TRUE
J 2
(-1025 2825);
DISPLAY 0.872340 (-1025 2825);
DISPLAY INVISIBLE (-1025 2825);
FORCEPROP 1 LAST PATH I70
J 2
(-698 2950);
DISPLAY 0.872340 (-698 2950);
PAINT GREEN (-698 2950);
DISPLAY INVISIBLE (-698 2950);
FORCEADD TAP..1
R 2
(-700 3100);
FORCEPROP 3 LASTPIN (-650 3100) SIG_NAME M_E_CPU0_SA_DQ<13>
J 0
(-640 3110);
DISPLAY 0.659574 (-640 3110);
PAINT MONO (-640 3110);
DISPLAY INVISIBLE (-640 3110);
FORCEPROP 1 LASTPIN (-650 3100) BN 13
J 2
(-638 3108);
DISPLAY 0.680851 (-638 3108);
PAINT GREEN (-638 3108);
FORCEPROP 2 LAST CDS_LIB standard
J 0
(-700 3100);
DISPLAY INVISIBLE (-700 3100);
FORCEPROP 1 LAST BODY_TYPE PLUMBING
J 2
(-700 3150);
DISPLAY 0.872340 (-700 3150);
PAINT GREEN (-700 3150);
DISPLAY INVISIBLE (-700 3150);
FORCEPROP 1 LAST HDL_TAP TRUE
J 2
(-1025 2975);
DISPLAY 0.872340 (-1025 2975);
DISPLAY INVISIBLE (-1025 2975);
FORCEPROP 1 LAST PATH I71
J 2
(-698 3100);
DISPLAY 0.872340 (-698 3100);
PAINT GREEN (-698 3100);
DISPLAY INVISIBLE (-698 3100);
FORCEADD TAP..1
R 2
(-700 3050);
FORCEPROP 3 LASTPIN (-650 3050) SIG_NAME M_E_CPU0_SA_DQ<12>
J 0
(-640 3060);
DISPLAY 0.659574 (-640 3060);
PAINT MONO (-640 3060);
DISPLAY INVISIBLE (-640 3060);
FORCEPROP 1 LASTPIN (-650 3050) BN 12
J 2
(-638 3058);
DISPLAY 0.680851 (-638 3058);
PAINT GREEN (-638 3058);
FORCEPROP 2 LAST CDS_LIB standard
J 0
(-700 3050);
DISPLAY INVISIBLE (-700 3050);
FORCEPROP 1 LAST BODY_TYPE PLUMBING
J 2
(-700 3100);
DISPLAY 0.872340 (-700 3100);
PAINT GREEN (-700 3100);
DISPLAY INVISIBLE (-700 3100);
FORCEPROP 1 LAST HDL_TAP TRUE
J 2
(-1025 2925);
DISPLAY 0.872340 (-1025 2925);
DISPLAY INVISIBLE (-1025 2925);
FORCEPROP 1 LAST PATH I72
J 2
(-698 3050);
DISPLAY 0.872340 (-698 3050);
PAINT GREEN (-698 3050);
DISPLAY INVISIBLE (-698 3050);
FORCEADD TAP..1
R 2
(-700 3150);
FORCEPROP 3 LASTPIN (-650 3150) SIG_NAME M_E_CPU0_SA_DQ<14>
J 0
(-640 3160);
DISPLAY 0.659574 (-640 3160);
PAINT MONO (-640 3160);
DISPLAY INVISIBLE (-640 3160);
FORCEPROP 1 LASTPIN (-650 3150) BN 14
J 2
(-638 3158);
DISPLAY 0.680851 (-638 3158);
PAINT GREEN (-638 3158);
FORCEPROP 2 LAST CDS_LIB standard
J 0
(-700 3150);
DISPLAY INVISIBLE (-700 3150);
FORCEPROP 1 LAST BODY_TYPE PLUMBING
J 2
(-700 3200);
DISPLAY 0.872340 (-700 3200);
PAINT GREEN (-700 3200);
DISPLAY INVISIBLE (-700 3200);
FORCEPROP 1 LAST HDL_TAP TRUE
J 2
(-1025 3025);
DISPLAY 0.872340 (-1025 3025);
DISPLAY INVISIBLE (-1025 3025);
FORCEPROP 1 LAST PATH I73
J 2
(-698 3150);
DISPLAY 0.872340 (-698 3150);
PAINT GREEN (-698 3150);
DISPLAY INVISIBLE (-698 3150);
FORCEADD TAP..1
R 2
(-700 3250);
FORCEPROP 3 LASTPIN (-650 3250) SIG_NAME M_E_CPU0_SA_DQ<16>
J 0
(-640 3260);
DISPLAY 0.659574 (-640 3260);
PAINT MONO (-640 3260);
DISPLAY INVISIBLE (-640 3260);
FORCEPROP 1 LASTPIN (-650 3250) BN 16
J 2
(-638 3258);
DISPLAY 0.680851 (-638 3258);
PAINT GREEN (-638 3258);
FORCEPROP 2 LAST CDS_LIB standard
J 0
(-700 3250);
DISPLAY INVISIBLE (-700 3250);
FORCEPROP 1 LAST BODY_TYPE PLUMBING
J 2
(-700 3300);
DISPLAY 0.872340 (-700 3300);
PAINT GREEN (-700 3300);
DISPLAY INVISIBLE (-700 3300);
FORCEPROP 1 LAST HDL_TAP TRUE
J 2
(-1025 3125);
DISPLAY 0.872340 (-1025 3125);
DISPLAY INVISIBLE (-1025 3125);
FORCEPROP 1 LAST PATH I74
J 2
(-698 3250);
DISPLAY 0.872340 (-698 3250);
PAINT GREEN (-698 3250);
DISPLAY INVISIBLE (-698 3250);
FORCEADD TAP..1
R 2
(-700 3200);
FORCEPROP 3 LASTPIN (-650 3200) SIG_NAME M_E_CPU0_SA_DQ<15>
J 0
(-640 3210);
DISPLAY 0.659574 (-640 3210);
PAINT MONO (-640 3210);
DISPLAY INVISIBLE (-640 3210);
FORCEPROP 1 LASTPIN (-650 3200) BN 15
J 2
(-638 3208);
DISPLAY 0.680851 (-638 3208);
PAINT GREEN (-638 3208);
FORCEPROP 2 LAST CDS_LIB standard
J 0
(-700 3200);
DISPLAY INVISIBLE (-700 3200);
FORCEPROP 1 LAST BODY_TYPE PLUMBING
J 2
(-700 3250);
DISPLAY 0.872340 (-700 3250);
PAINT GREEN (-700 3250);
DISPLAY INVISIBLE (-700 3250);
FORCEPROP 1 LAST HDL_TAP TRUE
J 2
(-1025 3075);
DISPLAY 0.872340 (-1025 3075);
DISPLAY INVISIBLE (-1025 3075);
FORCEPROP 1 LAST PATH I75
J 2
(-698 3200);
DISPLAY 0.872340 (-698 3200);
PAINT GREEN (-698 3200);
DISPLAY INVISIBLE (-698 3200);
FORCEADD TAP..1
R 2
(-700 3300);
FORCEPROP 3 LASTPIN (-650 3300) SIG_NAME M_E_CPU0_SA_DQ<17>
J 0
(-640 3310);
DISPLAY 0.659574 (-640 3310);
PAINT MONO (-640 3310);
DISPLAY INVISIBLE (-640 3310);
FORCEPROP 1 LASTPIN (-650 3300) BN 17
J 2
(-638 3308);
DISPLAY 0.680851 (-638 3308);
PAINT GREEN (-638 3308);
FORCEPROP 2 LAST CDS_LIB standard
J 0
(-700 3300);
DISPLAY INVISIBLE (-700 3300);
FORCEPROP 1 LAST BODY_TYPE PLUMBING
J 2
(-700 3350);
DISPLAY 0.872340 (-700 3350);
PAINT GREEN (-700 3350);
DISPLAY INVISIBLE (-700 3350);
FORCEPROP 1 LAST HDL_TAP TRUE
J 2
(-1025 3175);
DISPLAY 0.872340 (-1025 3175);
DISPLAY INVISIBLE (-1025 3175);
FORCEPROP 1 LAST PATH I76
J 2
(-698 3300);
DISPLAY 0.872340 (-698 3300);
PAINT GREEN (-698 3300);
DISPLAY INVISIBLE (-698 3300);
FORCEADD TAP..1
R 2
(-700 3400);
FORCEPROP 3 LASTPIN (-650 3400) SIG_NAME M_E_CPU0_SA_DQ<19>
J 0
(-640 3410);
DISPLAY 0.659574 (-640 3410);
PAINT MONO (-640 3410);
DISPLAY INVISIBLE (-640 3410);
FORCEPROP 1 LASTPIN (-650 3400) BN 19
J 2
(-638 3408);
DISPLAY 0.680851 (-638 3408);
PAINT GREEN (-638 3408);
FORCEPROP 2 LAST CDS_LIB standard
J 0
(-700 3400);
DISPLAY INVISIBLE (-700 3400);
FORCEPROP 1 LAST BODY_TYPE PLUMBING
J 2
(-700 3450);
DISPLAY 0.872340 (-700 3450);
PAINT GREEN (-700 3450);
DISPLAY INVISIBLE (-700 3450);
FORCEPROP 1 LAST HDL_TAP TRUE
J 2
(-1025 3275);
DISPLAY 0.872340 (-1025 3275);
DISPLAY INVISIBLE (-1025 3275);
FORCEPROP 1 LAST PATH I77
J 2
(-698 3400);
DISPLAY 0.872340 (-698 3400);
PAINT GREEN (-698 3400);
DISPLAY INVISIBLE (-698 3400);
FORCEADD TAP..1
R 2
(-700 3350);
FORCEPROP 3 LASTPIN (-650 3350) SIG_NAME M_E_CPU0_SA_DQ<18>
J 0
(-640 3360);
DISPLAY 0.659574 (-640 3360);
PAINT MONO (-640 3360);
DISPLAY INVISIBLE (-640 3360);
FORCEPROP 1 LASTPIN (-650 3350) BN 18
J 2
(-638 3358);
DISPLAY 0.680851 (-638 3358);
PAINT GREEN (-638 3358);
FORCEPROP 2 LAST CDS_LIB standard
J 0
(-700 3350);
DISPLAY INVISIBLE (-700 3350);
FORCEPROP 1 LAST BODY_TYPE PLUMBING
J 2
(-700 3400);
DISPLAY 0.872340 (-700 3400);
PAINT GREEN (-700 3400);
DISPLAY INVISIBLE (-700 3400);
FORCEPROP 1 LAST HDL_TAP TRUE
J 2
(-1025 3225);
DISPLAY 0.872340 (-1025 3225);
DISPLAY INVISIBLE (-1025 3225);
FORCEPROP 1 LAST PATH I78
J 2
(-698 3350);
DISPLAY 0.872340 (-698 3350);
PAINT GREEN (-698 3350);
DISPLAY INVISIBLE (-698 3350);
FORCEADD TAP..1
R 2
(-700 3500);
FORCEPROP 3 LASTPIN (-650 3500) SIG_NAME M_E_CPU0_SA_DQ<21>
J 0
(-640 3510);
DISPLAY 0.659574 (-640 3510);
PAINT MONO (-640 3510);
DISPLAY INVISIBLE (-640 3510);
FORCEPROP 1 LASTPIN (-650 3500) BN 21
J 2
(-638 3508);
DISPLAY 0.680851 (-638 3508);
PAINT GREEN (-638 3508);
FORCEPROP 2 LAST CDS_LIB standard
J 0
(-700 3500);
DISPLAY INVISIBLE (-700 3500);
FORCEPROP 1 LAST BODY_TYPE PLUMBING
J 2
(-700 3550);
DISPLAY 0.872340 (-700 3550);
PAINT GREEN (-700 3550);
DISPLAY INVISIBLE (-700 3550);
FORCEPROP 1 LAST HDL_TAP TRUE
J 2
(-1025 3375);
DISPLAY 0.872340 (-1025 3375);
DISPLAY INVISIBLE (-1025 3375);
FORCEPROP 1 LAST PATH I79
J 2
(-698 3500);
DISPLAY 0.872340 (-698 3500);
PAINT GREEN (-698 3500);
DISPLAY INVISIBLE (-698 3500);
FORCEADD TAP..1
R 2
(-700 100);
FORCEPROP 3 LASTPIN (-650 100) SIG_NAME M_E_CPU0_SB_CB<1>
J 0
(-640 110);
DISPLAY 0.659574 (-640 110);
PAINT MONO (-640 110);
DISPLAY INVISIBLE (-640 110);
FORCEPROP 1 LASTPIN (-650 100) BN 1
J 2
(-638 108);
DISPLAY 0.680851 (-638 108);
PAINT GREEN (-638 108);
FORCEPROP 2 LAST CDS_LIB standard
J 0
(-700 100);
DISPLAY INVISIBLE (-700 100);
FORCEPROP 1 LAST BODY_TYPE PLUMBING
J 2
(-700 150);
DISPLAY 0.872340 (-700 150);
PAINT GREEN (-700 150);
DISPLAY INVISIBLE (-700 150);
FORCEPROP 1 LAST HDL_TAP TRUE
J 2
(-1025 -25);
DISPLAY 0.872340 (-1025 -25);
DISPLAY INVISIBLE (-1025 -25);
FORCEPROP 1 LAST PATH I8
J 2
(-698 100);
DISPLAY 0.872340 (-698 100);
PAINT GREEN (-698 100);
DISPLAY INVISIBLE (-698 100);
FORCEADD TAP..1
R 2
(-700 3450);
FORCEPROP 3 LASTPIN (-650 3450) SIG_NAME M_E_CPU0_SA_DQ<20>
J 0
(-640 3460);
DISPLAY 0.659574 (-640 3460);
PAINT MONO (-640 3460);
DISPLAY INVISIBLE (-640 3460);
FORCEPROP 1 LASTPIN (-650 3450) BN 20
J 2
(-638 3458);
DISPLAY 0.680851 (-638 3458);
PAINT GREEN (-638 3458);
FORCEPROP 2 LAST CDS_LIB standard
J 0
(-700 3450);
DISPLAY INVISIBLE (-700 3450);
FORCEPROP 1 LAST BODY_TYPE PLUMBING
J 2
(-700 3500);
DISPLAY 0.872340 (-700 3500);
PAINT GREEN (-700 3500);
DISPLAY INVISIBLE (-700 3500);
FORCEPROP 1 LAST HDL_TAP TRUE
J 2
(-1025 3325);
DISPLAY 0.872340 (-1025 3325);
DISPLAY INVISIBLE (-1025 3325);
FORCEPROP 1 LAST PATH I80
J 2
(-698 3450);
DISPLAY 0.872340 (-698 3450);
PAINT GREEN (-698 3450);
DISPLAY INVISIBLE (-698 3450);
FORCEADD TAP..1
R 2
(-700 3550);
FORCEPROP 3 LASTPIN (-650 3550) SIG_NAME M_E_CPU0_SA_DQ<22>
J 0
(-640 3560);
DISPLAY 0.659574 (-640 3560);
PAINT MONO (-640 3560);
DISPLAY INVISIBLE (-640 3560);
FORCEPROP 1 LASTPIN (-650 3550) BN 22
J 2
(-638 3558);
DISPLAY 0.680851 (-638 3558);
PAINT GREEN (-638 3558);
FORCEPROP 2 LAST CDS_LIB standard
J 0
(-700 3550);
DISPLAY INVISIBLE (-700 3550);
FORCEPROP 1 LAST BODY_TYPE PLUMBING
J 2
(-700 3600);
DISPLAY 0.872340 (-700 3600);
PAINT GREEN (-700 3600);
DISPLAY INVISIBLE (-700 3600);
FORCEPROP 1 LAST HDL_TAP TRUE
J 2
(-1025 3425);
DISPLAY 0.872340 (-1025 3425);
DISPLAY INVISIBLE (-1025 3425);
FORCEPROP 1 LAST PATH I81
J 2
(-698 3550);
DISPLAY 0.872340 (-698 3550);
PAINT GREEN (-698 3550);
DISPLAY INVISIBLE (-698 3550);
FORCEADD TAP..1
R 2
(-700 3600);
FORCEPROP 3 LASTPIN (-650 3600) SIG_NAME M_E_CPU0_SA_DQ<23>
J 0
(-640 3610);
DISPLAY 0.659574 (-640 3610);
PAINT MONO (-640 3610);
DISPLAY INVISIBLE (-640 3610);
FORCEPROP 1 LASTPIN (-650 3600) BN 23
J 2
(-638 3608);
DISPLAY 0.680851 (-638 3608);
PAINT GREEN (-638 3608);
FORCEPROP 2 LAST CDS_LIB standard
J 0
(-700 3600);
DISPLAY INVISIBLE (-700 3600);
FORCEPROP 1 LAST BODY_TYPE PLUMBING
J 2
(-700 3650);
DISPLAY 0.872340 (-700 3650);
PAINT GREEN (-700 3650);
DISPLAY INVISIBLE (-700 3650);
FORCEPROP 1 LAST HDL_TAP TRUE
J 2
(-1025 3475);
DISPLAY 0.872340 (-1025 3475);
DISPLAY INVISIBLE (-1025 3475);
FORCEPROP 1 LAST PATH I82
J 2
(-698 3600);
DISPLAY 0.872340 (-698 3600);
PAINT GREEN (-698 3600);
DISPLAY INVISIBLE (-698 3600);
FORCEADD TAP..1
R 2
(-700 3650);
FORCEPROP 3 LASTPIN (-650 3650) SIG_NAME M_E_CPU0_SA_DQ<24>
J 0
(-640 3660);
DISPLAY 0.659574 (-640 3660);
PAINT MONO (-640 3660);
DISPLAY INVISIBLE (-640 3660);
FORCEPROP 1 LASTPIN (-650 3650) BN 24
J 2
(-638 3658);
DISPLAY 0.680851 (-638 3658);
PAINT GREEN (-638 3658);
FORCEPROP 2 LAST CDS_LIB standard
J 0
(-700 3650);
DISPLAY INVISIBLE (-700 3650);
FORCEPROP 1 LAST BODY_TYPE PLUMBING
J 2
(-700 3700);
DISPLAY 0.872340 (-700 3700);
PAINT GREEN (-700 3700);
DISPLAY INVISIBLE (-700 3700);
FORCEPROP 1 LAST HDL_TAP TRUE
J 2
(-1025 3525);
DISPLAY 0.872340 (-1025 3525);
DISPLAY INVISIBLE (-1025 3525);
FORCEPROP 1 LAST PATH I83
J 2
(-698 3650);
DISPLAY 0.872340 (-698 3650);
PAINT GREEN (-698 3650);
DISPLAY INVISIBLE (-698 3650);
FORCEADD TAP..1
R 2
(-700 3750);
FORCEPROP 3 LASTPIN (-650 3750) SIG_NAME M_E_CPU0_SA_DQ<26>
J 0
(-640 3760);
DISPLAY 0.659574 (-640 3760);
PAINT MONO (-640 3760);
DISPLAY INVISIBLE (-640 3760);
FORCEPROP 1 LASTPIN (-650 3750) BN 26
J 2
(-638 3758);
DISPLAY 0.680851 (-638 3758);
PAINT GREEN (-638 3758);
FORCEPROP 2 LAST CDS_LIB standard
J 0
(-700 3750);
DISPLAY INVISIBLE (-700 3750);
FORCEPROP 1 LAST BODY_TYPE PLUMBING
J 2
(-700 3800);
DISPLAY 0.872340 (-700 3800);
PAINT GREEN (-700 3800);
DISPLAY INVISIBLE (-700 3800);
FORCEPROP 1 LAST HDL_TAP TRUE
J 2
(-1025 3625);
DISPLAY 0.872340 (-1025 3625);
DISPLAY INVISIBLE (-1025 3625);
FORCEPROP 1 LAST PATH I84
J 2
(-698 3750);
DISPLAY 0.872340 (-698 3750);
PAINT GREEN (-698 3750);
DISPLAY INVISIBLE (-698 3750);
FORCEADD TAP..1
R 2
(-700 3700);
FORCEPROP 3 LASTPIN (-650 3700) SIG_NAME M_E_CPU0_SA_DQ<25>
J 0
(-640 3710);
DISPLAY 0.659574 (-640 3710);
PAINT MONO (-640 3710);
DISPLAY INVISIBLE (-640 3710);
FORCEPROP 1 LASTPIN (-650 3700) BN 25
J 2
(-638 3708);
DISPLAY 0.680851 (-638 3708);
PAINT GREEN (-638 3708);
FORCEPROP 2 LAST CDS_LIB standard
J 0
(-700 3700);
DISPLAY INVISIBLE (-700 3700);
FORCEPROP 1 LAST BODY_TYPE PLUMBING
J 2
(-700 3750);
DISPLAY 0.872340 (-700 3750);
PAINT GREEN (-700 3750);
DISPLAY INVISIBLE (-700 3750);
FORCEPROP 1 LAST HDL_TAP TRUE
J 2
(-1025 3575);
DISPLAY 0.872340 (-1025 3575);
DISPLAY INVISIBLE (-1025 3575);
FORCEPROP 1 LAST PATH I85
J 2
(-698 3700);
DISPLAY 0.872340 (-698 3700);
PAINT GREEN (-698 3700);
DISPLAY INVISIBLE (-698 3700);
FORCEADD TAP..1
R 2
(-700 3800);
FORCEPROP 3 LASTPIN (-650 3800) SIG_NAME M_E_CPU0_SA_DQ<27>
J 0
(-640 3810);
DISPLAY 0.659574 (-640 3810);
PAINT MONO (-640 3810);
DISPLAY INVISIBLE (-640 3810);
FORCEPROP 1 LASTPIN (-650 3800) BN 27
J 2
(-638 3808);
DISPLAY 0.680851 (-638 3808);
PAINT GREEN (-638 3808);
FORCEPROP 2 LAST CDS_LIB standard
J 0
(-700 3800);
DISPLAY INVISIBLE (-700 3800);
FORCEPROP 1 LAST BODY_TYPE PLUMBING
J 2
(-700 3850);
DISPLAY 0.872340 (-700 3850);
PAINT GREEN (-700 3850);
DISPLAY INVISIBLE (-700 3850);
FORCEPROP 1 LAST HDL_TAP TRUE
J 2
(-1025 3675);
DISPLAY 0.872340 (-1025 3675);
DISPLAY INVISIBLE (-1025 3675);
FORCEPROP 1 LAST PATH I86
J 2
(-698 3800);
DISPLAY 0.872340 (-698 3800);
PAINT GREEN (-698 3800);
DISPLAY INVISIBLE (-698 3800);
FORCEADD TAP..1
R 2
(-700 3900);
FORCEPROP 3 LASTPIN (-650 3900) SIG_NAME M_E_CPU0_SA_DQ<29>
J 0
(-640 3910);
DISPLAY 0.659574 (-640 3910);
PAINT MONO (-640 3910);
DISPLAY INVISIBLE (-640 3910);
FORCEPROP 1 LASTPIN (-650 3900) BN 29
J 2
(-638 3908);
DISPLAY 0.680851 (-638 3908);
PAINT GREEN (-638 3908);
FORCEPROP 2 LAST CDS_LIB standard
J 0
(-700 3900);
DISPLAY INVISIBLE (-700 3900);
FORCEPROP 1 LAST BODY_TYPE PLUMBING
J 2
(-700 3950);
DISPLAY 0.872340 (-700 3950);
PAINT GREEN (-700 3950);
DISPLAY INVISIBLE (-700 3950);
FORCEPROP 1 LAST HDL_TAP TRUE
J 2
(-1025 3775);
DISPLAY 0.872340 (-1025 3775);
DISPLAY INVISIBLE (-1025 3775);
FORCEPROP 1 LAST PATH I87
J 2
(-698 3900);
DISPLAY 0.872340 (-698 3900);
PAINT GREEN (-698 3900);
DISPLAY INVISIBLE (-698 3900);
FORCEADD TAP..1
R 2
(-700 3850);
FORCEPROP 3 LASTPIN (-650 3850) SIG_NAME M_E_CPU0_SA_DQ<28>
J 0
(-640 3860);
DISPLAY 0.659574 (-640 3860);
PAINT MONO (-640 3860);
DISPLAY INVISIBLE (-640 3860);
FORCEPROP 1 LASTPIN (-650 3850) BN 28
J 2
(-638 3858);
DISPLAY 0.680851 (-638 3858);
PAINT GREEN (-638 3858);
FORCEPROP 2 LAST CDS_LIB standard
J 0
(-700 3850);
DISPLAY INVISIBLE (-700 3850);
FORCEPROP 1 LAST BODY_TYPE PLUMBING
J 2
(-700 3900);
DISPLAY 0.872340 (-700 3900);
PAINT GREEN (-700 3900);
DISPLAY INVISIBLE (-700 3900);
FORCEPROP 1 LAST HDL_TAP TRUE
J 2
(-1025 3725);
DISPLAY 0.872340 (-1025 3725);
DISPLAY INVISIBLE (-1025 3725);
FORCEPROP 1 LAST PATH I88
J 2
(-698 3850);
DISPLAY 0.872340 (-698 3850);
PAINT GREEN (-698 3850);
DISPLAY INVISIBLE (-698 3850);
FORCEADD TAP..1
R 2
(-700 3950);
FORCEPROP 3 LASTPIN (-650 3950) SIG_NAME M_E_CPU0_SA_DQ<30>
J 0
(-640 3960);
DISPLAY 0.659574 (-640 3960);
PAINT MONO (-640 3960);
DISPLAY INVISIBLE (-640 3960);
FORCEPROP 1 LASTPIN (-650 3950) BN 30
J 2
(-638 3958);
DISPLAY 0.680851 (-638 3958);
PAINT GREEN (-638 3958);
FORCEPROP 2 LAST CDS_LIB standard
J 0
(-700 3950);
DISPLAY INVISIBLE (-700 3950);
FORCEPROP 1 LAST BODY_TYPE PLUMBING
J 2
(-700 4000);
DISPLAY 0.872340 (-700 4000);
PAINT GREEN (-700 4000);
DISPLAY INVISIBLE (-700 4000);
FORCEPROP 1 LAST HDL_TAP TRUE
J 2
(-1025 3825);
DISPLAY 0.872340 (-1025 3825);
DISPLAY INVISIBLE (-1025 3825);
FORCEPROP 1 LAST PATH I89
J 2
(-698 3950);
DISPLAY 0.872340 (-698 3950);
PAINT GREEN (-698 3950);
DISPLAY INVISIBLE (-698 3950);
FORCEADD OFFPAGE..3
R 2
(-1725 425);
FORCEPROP 2 LAST $XR1 91 
J 0
(-2094 425);
DISPLAY 0.638298 (-2094 425);
PAINT MONO (-2094 425);
FORCEPROP 2 LAST $XR0 90 
J 0
(-2004 425);
DISPLAY 0.638298 (-2004 425);
PAINT MONO (-2004 425);
FORCEPROP 2 LAST CDS_LIB standard
J 0
(-1725 425);
DISPLAY INVISIBLE (-1725 425);
FORCEPROP 1 LAST OFFPAGE TRUE
J 2
(-2050 300);
DISPLAY 0.872340 (-2050 300);
DISPLAY INVISIBLE (-2050 300);
FORCEPROP 1 LAST COMMENT_BODY TRUE
J 2
(-1675 325);
DISPLAY 0.872340 (-1675 325);
PAINT GREEN (-1675 325);
DISPLAY INVISIBLE (-1675 325);
FORCEPROP 2 LAST PATH I9
J 0
(-1675 500);
DISPLAY 1.021277 (-1675 500);
DISPLAY INVISIBLE (-1675 500);
FORCEADD TAP..1
R 2
(-700 4000);
FORCEPROP 3 LASTPIN (-650 4000) SIG_NAME M_E_CPU0_SA_DQ<31>
J 0
(-640 4010);
DISPLAY 0.659574 (-640 4010);
PAINT MONO (-640 4010);
DISPLAY INVISIBLE (-640 4010);
FORCEPROP 1 LASTPIN (-650 4000) BN 31
J 2
(-638 4008);
DISPLAY 0.680851 (-638 4008);
PAINT GREEN (-638 4008);
FORCEPROP 2 LAST CDS_LIB standard
J 0
(-700 4000);
DISPLAY INVISIBLE (-700 4000);
FORCEPROP 1 LAST BODY_TYPE PLUMBING
J 2
(-700 4050);
DISPLAY 0.872340 (-700 4050);
PAINT GREEN (-700 4050);
DISPLAY INVISIBLE (-700 4050);
FORCEPROP 1 LAST HDL_TAP TRUE
J 2
(-1025 3875);
DISPLAY 0.872340 (-1025 3875);
DISPLAY INVISIBLE (-1025 3875);
FORCEPROP 1 LAST PATH I90
J 2
(-698 4000);
DISPLAY 0.872340 (-698 4000);
PAINT GREEN (-698 4000);
DISPLAY INVISIBLE (-698 4000);
FORCEADD OFFPAGE..4
(3825 -200);
FORCEPROP 2 LAST $XR1 91 
J 0
(4101 -200);
DISPLAY 0.638298 (4101 -200);
PAINT MONO (4101 -200);
FORCEPROP 2 LAST $XR0 90 
J 0
(4011 -200);
DISPLAY 0.638298 (4011 -200);
PAINT MONO (4011 -200);
FORCEPROP 2 LAST CDS_LIB standard
J 0
(3825 -200);
PAINT MONO (3825 -200);
DISPLAY INVISIBLE (3825 -200);
FORCEPROP 1 LAST OFFPAGE TRUE
J 0
(4150 -325);
DISPLAY 1.170213 (4150 -325);
PAINT GREEN (4150 -325);
DISPLAY INVISIBLE (4150 -325);
FORCEPROP 1 LAST COMMENT_BODY TRUE
J 0
(3800 -300);
DISPLAY 1.170213 (3800 -300);
PAINT GREEN (3800 -300);
DISPLAY INVISIBLE (3800 -300);
FORCEPROP 2 LAST PATH I92
J 0
(4000 -125);
DISPLAY 1.021277 (4000 -125);
DISPLAY INVISIBLE (4000 -125);
FORCEADD OFFPAGE..4
(3825 50);
FORCEPROP 2 LAST $XR0 90 
J 0
(4011 50);
DISPLAY 0.638298 (4011 50);
PAINT MONO (4011 50);
FORCEPROP 2 LAST CDS_LIB standard
J 0
(3825 50);
PAINT MONO (3825 50);
DISPLAY INVISIBLE (3825 50);
FORCEPROP 1 LAST OFFPAGE TRUE
J 0
(4150 -75);
DISPLAY 1.170213 (4150 -75);
PAINT GREEN (4150 -75);
DISPLAY INVISIBLE (4150 -75);
FORCEPROP 1 LAST COMMENT_BODY TRUE
J 0
(3800 -50);
DISPLAY 1.170213 (3800 -50);
PAINT GREEN (3800 -50);
DISPLAY INVISIBLE (3800 -50);
FORCEPROP 2 LAST PATH I93
J 0
(4000 125);
DISPLAY 1.021277 (4000 125);
DISPLAY INVISIBLE (4000 125);
FORCEADD OFFPAGE..4
(3825 -50);
FORCEPROP 2 LAST $XR0 91 
J 0
(4011 -50);
DISPLAY 0.638298 (4011 -50);
PAINT MONO (4011 -50);
FORCEPROP 2 LAST CDS_LIB standard
J 0
(3825 -50);
PAINT MONO (3825 -50);
DISPLAY INVISIBLE (3825 -50);
FORCEPROP 1 LAST OFFPAGE TRUE
J 0
(4150 -175);
DISPLAY 1.170213 (4150 -175);
PAINT GREEN (4150 -175);
DISPLAY INVISIBLE (4150 -175);
FORCEPROP 1 LAST COMMENT_BODY TRUE
J 0
(3800 -150);
DISPLAY 1.170213 (3800 -150);
PAINT GREEN (3800 -150);
DISPLAY INVISIBLE (3800 -150);
FORCEPROP 2 LAST PATH I94
J 0
(4000 25);
DISPLAY 1.021277 (4000 25);
DISPLAY INVISIBLE (4000 25);
FORCEADD OFFPAGE..4
(3825 -100);
FORCEPROP 2 LAST $XR0 90 
J 0
(4011 -100);
DISPLAY 0.638298 (4011 -100);
PAINT MONO (4011 -100);
FORCEPROP 2 LAST CDS_LIB standard
J 0
(3825 -100);
PAINT MONO (3825 -100);
DISPLAY INVISIBLE (3825 -100);
FORCEPROP 1 LAST OFFPAGE TRUE
J 0
(4150 -225);
DISPLAY 1.170213 (4150 -225);
PAINT GREEN (4150 -225);
DISPLAY INVISIBLE (4150 -225);
FORCEPROP 1 LAST COMMENT_BODY TRUE
J 0
(3800 -200);
DISPLAY 1.170213 (3800 -200);
PAINT GREEN (3800 -200);
DISPLAY INVISIBLE (3800 -200);
FORCEPROP 2 LAST PATH I95
J 0
(4000 -25);
DISPLAY 1.021277 (4000 -25);
DISPLAY INVISIBLE (4000 -25);
FORCEADD OFFPAGE..4
(3825 100);
FORCEPROP 2 LAST $XR0 91 
J 0
(4011 100);
DISPLAY 0.638298 (4011 100);
PAINT MONO (4011 100);
FORCEPROP 2 LAST CDS_LIB standard
J 0
(3825 100);
PAINT MONO (3825 100);
DISPLAY INVISIBLE (3825 100);
FORCEPROP 1 LAST OFFPAGE TRUE
J 0
(4150 -25);
DISPLAY 1.170213 (4150 -25);
PAINT GREEN (4150 -25);
DISPLAY INVISIBLE (4150 -25);
FORCEPROP 1 LAST COMMENT_BODY TRUE
J 0
(3800 0);
DISPLAY 1.170213 (3800 0);
PAINT GREEN (3800 0);
DISPLAY INVISIBLE (3800 0);
FORCEPROP 2 LAST PATH I96
J 0
(4000 175);
DISPLAY 1.021277 (4000 175);
DISPLAY INVISIBLE (4000 175);
FORCEADD TAP..1
(2725 350);
FORCEPROP 3 LASTPIN (2675 350) SIG_NAME M_E_CPU0_SB_CS_N<2>
J 0
(2685 360);
DISPLAY 0.659574 (2685 360);
PAINT MONO (2685 360);
DISPLAY INVISIBLE (2685 360);
FORCEPROP 1 LASTPIN (2675 350) BN 2
J 0
(2663 358);
DISPLAY 0.680851 (2663 358);
PAINT GREEN (2663 358);
FORCEPROP 2 LAST CDS_LIB standard
J 0
(2725 350);
DISPLAY INVISIBLE (2725 350);
FORCEPROP 1 LAST BODY_TYPE PLUMBING
J 0
(2725 400);
DISPLAY 0.872340 (2725 400);
PAINT GREEN (2725 400);
DISPLAY INVISIBLE (2725 400);
FORCEPROP 1 LAST HDL_TAP TRUE
J 0
(3050 225);
DISPLAY 0.872340 (3050 225);
DISPLAY INVISIBLE (3050 225);
FORCEPROP 1 LAST PATH I97
J 0
(2723 350);
DISPLAY 0.872340 (2723 350);
PAINT GREEN (2723 350);
DISPLAY INVISIBLE (2723 350);
FORCEADD TAP..1
(2725 300);
FORCEPROP 3 LASTPIN (2675 300) SIG_NAME M_E_CPU0_SB_CS_N<1>
J 0
(2685 310);
DISPLAY 0.659574 (2685 310);
PAINT MONO (2685 310);
DISPLAY INVISIBLE (2685 310);
FORCEPROP 1 LASTPIN (2675 300) BN 1
J 0
(2663 308);
DISPLAY 0.680851 (2663 308);
PAINT GREEN (2663 308);
FORCEPROP 2 LAST CDS_LIB standard
J 0
(2725 300);
DISPLAY INVISIBLE (2725 300);
FORCEPROP 1 LAST BODY_TYPE PLUMBING
J 0
(2725 350);
DISPLAY 0.872340 (2725 350);
PAINT GREEN (2725 350);
DISPLAY INVISIBLE (2725 350);
FORCEPROP 1 LAST HDL_TAP TRUE
J 0
(3050 175);
DISPLAY 0.872340 (3050 175);
DISPLAY INVISIBLE (3050 175);
FORCEPROP 1 LAST PATH I98
J 0
(2723 300);
DISPLAY 0.872340 (2723 300);
PAINT GREEN (2723 300);
DISPLAY INVISIBLE (2723 300);
FORCEADD TAP..1
(2725 250);
FORCEPROP 3 LASTPIN (2675 250) SIG_NAME M_E_CPU0_SB_CS_N<0>
J 0
(2685 260);
DISPLAY 0.659574 (2685 260);
PAINT MONO (2685 260);
DISPLAY INVISIBLE (2685 260);
FORCEPROP 1 LASTPIN (2675 250) BN 0
J 0
(2663 258);
DISPLAY 0.680851 (2663 258);
PAINT GREEN (2663 258);
FORCEPROP 2 LAST CDS_LIB standard
J 0
(2725 250);
DISPLAY INVISIBLE (2725 250);
FORCEPROP 1 LAST BODY_TYPE PLUMBING
J 0
(2725 300);
DISPLAY 0.872340 (2725 300);
PAINT GREEN (2725 300);
DISPLAY INVISIBLE (2725 300);
FORCEPROP 1 LAST HDL_TAP TRUE
J 0
(3050 125);
DISPLAY 0.872340 (3050 125);
DISPLAY INVISIBLE (3050 125);
FORCEPROP 1 LAST PATH I99
J 0
(2723 250);
DISPLAY 0.872340 (2723 250);
PAINT GREEN (2723 250);
DISPLAY INVISIBLE (2723 250);
FORCEADD QUANTA_TITLE_BLOCK_C..1
(5650 -1500);
FORCEPROP 0 LAST CDS_CON_LAST_MODIFIED Fri Aug 25 14:00:09 2023
J 0
(3765 -1485);
PAINT MONO (3765 -1485);
DISPLAY INVISIBLE (3765 -1485);
FORCEPROP 1 LAST CUSTOM_TXT_CDS <CON_LAST_MODIFIED>
J 0
(3765 -1485);
DISPLAY 0.978723 (3765 -1485);
FORCEPROP 2 LAST CUSTOM_TXT_CDS <XR_PAGE_TITLE>
J 0
(-2240 3750);
DISPLAY 0.638298 (-2240 3750);
PAINT PINK (-2240 3750);
DISPLAY INVISIBLE (-2240 3750);
FORCEPROP 2 LAST CUSTOM_TXT_CDS <Q_NUMBER>
J 0
(4247 -1397);
DISPLAY 1.212766 (4247 -1397);
FORCEPROP 2 LAST CUSTOM_TXT_CDS 01
J 0
(5466 -1397);
DISPLAY 1.212766 (5466 -1397);
FORCEPROP 1 LAST CUSTOM_TXT_CDS <NAME_2>
J 0
(2475 -1450);
FORCEPROP 1 LAST CUSTOM_TXT_CDS <NAME_1>
J 0
(2475 -1325);
FORCEPROP 1 LAST CUSTOM_TXT_CDS <Q_PROJ>
J 0
(3268 -1398);
DISPLAY 1.212766 (3268 -1398);
FORCEPROP 1 LAST CUSTOM_TXT_CDS <Q_REV>
J 0
(5466 -1397);
DISPLAY 1.212766 (5466 -1397);
FORCEPROP 1 LAST CUSTOM_TXT_CDS <CON_PAGE_NUM> OF <CON_TOTAL_PAGES>
J 0
(5204 -1482);
DISPLAY 0.978723 (5204 -1482);
FORCEPROP 1 LAST Q_TITLE SPR CPU0 - DDR CH E (12 OF 30)
J 0
(-3716 -1474);
DISPLAY 1.957447 (-3716 -1474);
PAINT GREEN (-3716 -1474);
FORCEPROP 1 LAST Q_DEPT 
J 1
(1887 -1451);
DISPLAY 1.957447 (1887 -1451);
PAINT GREEN (1887 -1451);
FORCEPROP 2 LAST CDS_LIB pure_quanta
J 0
(5650 -1500);
PAINT MONO (5650 -1500);
DISPLAY INVISIBLE (5650 -1500);
FORCEPROP 1 LAST CDS_LMAN_SYM_OUTLINE -9475,6775,100,-125
J 0
(5650 -1500);
DISPLAY 0.468085 (5650 -1500);
PAINT GREEN (5650 -1500);
DISPLAY INVISIBLE (5650 -1500);
FORCEPROP 2 LAST PAGE_BORDER TRUE
J 0
(-2240 3750);
DISPLAY 0.638298 (-2240 3750);
PAINT PINK (-2240 3750);
DISPLAY INVISIBLE (-2240 3750);
FORCEPROP 2 LAST CDS_XR_PAGE_TITLE CR-24 : @S9S_MB_2U_LIB.S9S_MB_2U(SCH_1):PAGE24
J 0
(-2240 3750);
DISPLAY 0.638298 (-2240 3750);
PAINT PINK (-2240 3750);
DISPLAY INVISIBLE (-2240 3750);
FORCEPROP 1 LAST COMMENT_BODY TRUE
J 0
(5662 -1513);
DISPLAY 0.978723 (5662 -1513);
PAINT GREEN (5662 -1513);
DISPLAY INVISIBLE (5662 -1513);
WIRE 17 -1 (2775 1675)(2775 1725);
WIRE 17 -1 (2775 1625)(2775 1675);
WIRE 17 -1 (2775 1725)(3775 1725);
FORCEPROP 2 LAST SIG_NAME M_E_CPU0_SA_CA<6:0>
J 0
(2915 1735);
DISPLAY 0.680851 (2915 1735);
PAINT WHITE (2915 1735);
WIRE 17 -1 (2775 1575)(2775 1625);
WIRE 17 -1 (2775 1525)(2775 1575);
WIRE 17 -1 (2775 1475)(2775 1525);
WIRE 17 -1 (2775 1425)(2775 1475);
WIRE 17 -1 (2775 675)(2775 725);
WIRE 17 -1 (2775 625)(2775 675);
WIRE 17 -1 (2775 725)(3775 725);
FORCEPROP 2 LAST SIG_NAME M_E_CPU0_SA_CS_N<3:0>
J 0
(2915 735);
DISPLAY 0.680851 (2915 735);
PAINT WHITE (2915 735);
WIRE 17 -1 (2775 575)(2775 625);
WIRE 17 -1 (2775 3425)(2775 3475);
WIRE 17 -1 (2775 3375)(2775 3425);
WIRE 17 -1 (2775 3475)(3775 3475);
FORCEPROP 2 LAST SIG_NAME M_E_CPU0_SA_DQS_DN<9:0>
J 0
(2915 3485);
DISPLAY 0.680851 (2915 3485);
PAINT WHITE (2915 3485);
WIRE 17 -1 (2775 3325)(2775 3375);
WIRE 17 -1 (2775 3275)(2775 3325);
WIRE 17 -1 (2775 3225)(2775 3275);
WIRE 17 -1 (2775 3175)(2775 3225);
WIRE 17 -1 (2775 3125)(2775 3175);
WIRE 17 -1 (2775 3075)(2775 3125);
WIRE 17 -1 (2775 3025)(2775 3075);
WIRE 17 -1 (2775 3975)(2775 4025);
WIRE 17 -1 (2775 3925)(2775 3975);
WIRE 17 -1 (2775 4025)(3775 4025);
FORCEPROP 2 LAST SIG_NAME M_E_CPU0_SA_DQS_DP<9:0>
J 0
(2915 4035);
DISPLAY 0.680851 (2915 4035);
PAINT WHITE (2915 4035);
WIRE 17 -1 (2775 3875)(2775 3925);
WIRE 17 -1 (2775 3825)(2775 3875);
WIRE 17 -1 (2775 3775)(2775 3825);
WIRE 17 -1 (2775 3725)(2775 3775);
WIRE 17 -1 (2775 3675)(2775 3725);
WIRE 17 -1 (2775 3625)(2775 3675);
WIRE 17 -1 (2775 3575)(2775 3625);
WIRE 17 -1 (2775 1175)(2775 1225);
WIRE 17 -1 (2775 1125)(2775 1175);
WIRE 17 -1 (2775 1225)(3775 1225);
FORCEPROP 2 LAST SIG_NAME M_E_CPU0_SB_CA<6:0>
J 0
(2915 1235);
DISPLAY 0.680851 (2915 1235);
PAINT WHITE (2915 1235);
WIRE 17 -1 (2775 1075)(2775 1125);
WIRE 17 -1 (2775 1025)(2775 1075);
WIRE 17 -1 (2775 975)(2775 1025);
WIRE 17 -1 (2775 925)(2775 975);
WIRE 17 -1 (2775 375)(2775 425);
WIRE 17 -1 (2775 325)(2775 375);
WIRE 17 -1 (2775 425)(3775 425);
FORCEPROP 2 LAST SIG_NAME M_E_CPU0_SB_CS_N<3:0>
J 0
(2915 435);
DISPLAY 0.680851 (2915 435);
PAINT WHITE (2915 435);
WIRE 17 -1 (2775 275)(2775 325);
WIRE 17 -1 (2775 2275)(2775 2325);
WIRE 17 -1 (2775 2225)(2775 2275);
WIRE 17 -1 (2775 2325)(3775 2325);
FORCEPROP 2 LAST SIG_NAME M_E_CPU0_SB_DQS_DN<9:0>
J 0
(2915 2335);
DISPLAY 0.680851 (2915 2335);
PAINT WHITE (2915 2335);
WIRE 17 -1 (2775 2175)(2775 2225);
WIRE 17 -1 (2775 2125)(2775 2175);
WIRE 17 -1 (2775 2075)(2775 2125);
WIRE 17 -1 (2775 2025)(2775 2075);
WIRE 17 -1 (2775 1975)(2775 2025);
WIRE 17 -1 (2775 1925)(2775 1975);
WIRE 17 -1 (2775 1875)(2775 1925);
WIRE 17 -1 (2775 2825)(2775 2875);
WIRE 17 -1 (2775 2775)(2775 2825);
WIRE 17 -1 (2775 2875)(3775 2875);
FORCEPROP 2 LAST SIG_NAME M_E_CPU0_SB_DQS_DP<9:0>
J 0
(2915 2885);
DISPLAY 0.680851 (2915 2885);
PAINT WHITE (2915 2885);
WIRE 17 -1 (2775 2725)(2775 2775);
WIRE 17 -1 (2775 2675)(2775 2725);
WIRE 17 -1 (2775 2625)(2775 2675);
WIRE 17 -1 (2775 2575)(2775 2625);
WIRE 17 -1 (2775 2525)(2775 2575);
WIRE 17 -1 (2775 2475)(2775 2525);
WIRE 17 -1 (2775 2425)(2775 2475);
WIRE 17 -1 (-750 75)(-750 125);
WIRE 17 -1 (-750 125)(-750 175);
WIRE 17 -1 (-750 175)(-750 225);
WIRE 17 -1 (-750 225)(-750 275);
WIRE 17 -1 (-750 275)(-750 325);
WIRE 17 -1 (-750 325)(-750 375);
WIRE 17 -1 (-750 375)(-750 425);
WIRE 17 -1 (-1675 425)(-750 425);
FORCEPROP 2 LAST SIG_NAME M_E_CPU0_SB_CB<7:0>
J 0
(-1535 435);
DISPLAY 0.680851 (-1535 435);
PAINT WHITE (-1535 435);
WIRE 17 -1 (-750 475)(-750 525);
WIRE 17 -1 (-750 525)(-750 575);
WIRE 17 -1 (-750 575)(-750 625);
WIRE 17 -1 (-750 625)(-750 675);
WIRE 17 -1 (-750 675)(-750 725);
WIRE 17 -1 (-750 725)(-750 775);
WIRE 17 -1 (-750 775)(-750 825);
WIRE 17 -1 (-750 825)(-750 875);
WIRE 17 -1 (-750 875)(-750 925);
WIRE 17 -1 (-750 925)(-750 975);
WIRE 17 -1 (-750 975)(-750 1025);
WIRE 17 -1 (-750 1025)(-750 1075);
WIRE 17 -1 (-750 1075)(-750 1125);
WIRE 17 -1 (-750 1125)(-750 1175);
WIRE 17 -1 (-750 1175)(-750 1225);
WIRE 17 -1 (-750 1225)(-750 1275);
WIRE 17 -1 (-750 1275)(-750 1325);
WIRE 17 -1 (-750 1325)(-750 1375);
WIRE 17 -1 (-750 1375)(-750 1425);
WIRE 17 -1 (-750 1425)(-750 1475);
WIRE 17 -1 (-750 1475)(-750 1525);
WIRE 17 -1 (-750 1525)(-750 1575);
WIRE 17 -1 (-750 1575)(-750 1625);
WIRE 17 -1 (-750 1625)(-750 1675);
WIRE 17 -1 (-750 1675)(-750 1725);
WIRE 17 -1 (-750 1725)(-750 1775);
WIRE 17 -1 (-750 1775)(-750 1825);
WIRE 17 -1 (-750 1825)(-750 1875);
WIRE 17 -1 (-750 1875)(-750 1925);
WIRE 17 -1 (-750 1925)(-750 1975);
WIRE 17 -1 (-750 1975)(-750 2025);
WIRE 17 -1 (-1675 2025)(-750 2025);
FORCEPROP 2 LAST SIG_NAME M_E_CPU0_SB_DQ<31:0>
J 0
(-1535 2035);
DISPLAY 0.680851 (-1535 2035);
PAINT WHITE (-1535 2035);
WIRE 17 -1 (-750 2075)(-750 2125);
WIRE 17 -1 (-750 2125)(-750 2175);
WIRE 17 -1 (-750 2175)(-750 2225);
WIRE 17 -1 (-750 2225)(-750 2275);
WIRE 17 -1 (-750 2275)(-750 2325);
WIRE 17 -1 (-750 2325)(-750 2375);
WIRE 17 -1 (-750 2375)(-750 2425);
WIRE 17 -1 (-1675 2425)(-750 2425);
FORCEPROP 2 LAST SIG_NAME M_E_CPU0_SA_CB<7:0>
J 0
(-1535 2435);
DISPLAY 0.680851 (-1535 2435);
PAINT WHITE (-1535 2435);
WIRE 17 -1 (-750 2475)(-750 2525);
WIRE 17 -1 (-750 2525)(-750 2575);
WIRE 17 -1 (-750 2575)(-750 2625);
WIRE 17 -1 (-750 2625)(-750 2675);
WIRE 17 -1 (-750 2675)(-750 2725);
WIRE 17 -1 (-750 2725)(-750 2775);
WIRE 17 -1 (-750 2775)(-750 2825);
WIRE 17 -1 (-750 2825)(-750 2875);
WIRE 17 -1 (-750 2875)(-750 2925);
WIRE 17 -1 (-750 2925)(-750 2975);
WIRE 17 -1 (-750 2975)(-750 3025);
WIRE 17 -1 (-750 3025)(-750 3075);
WIRE 17 -1 (-750 3075)(-750 3125);
WIRE 17 -1 (-750 3125)(-750 3175);
WIRE 17 -1 (-750 3175)(-750 3225);
WIRE 17 -1 (-750 3225)(-750 3275);
WIRE 17 -1 (-750 3275)(-750 3325);
WIRE 17 -1 (-750 3325)(-750 3375);
WIRE 17 -1 (-750 3375)(-750 3425);
WIRE 17 -1 (-750 3425)(-750 3475);
WIRE 17 -1 (-750 3475)(-750 3525);
WIRE 17 -1 (-750 3525)(-750 3575);
WIRE 17 -1 (-750 3575)(-750 3625);
WIRE 17 -1 (-750 3625)(-750 3675);
WIRE 17 -1 (-750 3675)(-750 3725);
WIRE 17 -1 (-750 3725)(-750 3775);
WIRE 17 -1 (-750 3775)(-750 3825);
WIRE 17 -1 (-750 3825)(-750 3875);
WIRE 17 -1 (-750 3875)(-750 3925);
WIRE 17 -1 (-750 3925)(-750 3975);
WIRE 17 -1 (-750 3975)(-750 4025);
WIRE 17 -1 (-1675 4025)(-750 4025);
FORCEPROP 2 LAST SIG_NAME M_E_CPU0_SA_DQ<31:0>
J 0
(-1535 4035);
DISPLAY 0.680851 (-1535 4035);
PAINT WHITE (-1535 4035);
WIRE 17 -1 (-750 -75)(-750 -25);
WIRE 17 -1 (-1675 -25)(-750 -25);
FORCEPROP 2 LAST SIG_NAME M_E_CPU0_CLK_DP<1:0>
J 0
(-1535 -15);
DISPLAY 0.680851 (-1535 -15);
PAINT WHITE (-1535 -15);
WIRE 17 -1 (-750 -175)(-750 -125);
WIRE 17 -1 (-1675 -125)(-750 -125);
FORCEPROP 2 LAST SIG_NAME M_E_CPU0_CLK_DN<1:0>
J 0
(-1535 -115);
DISPLAY 0.680851 (-1535 -115);
PAINT WHITE (-1535 -115);
WIRE 16 -1 (-650 3500)(-200 3500);
WIRE 16 -1 (-650 3450)(-200 3450);
WIRE 16 -1 (-650 3400)(-200 3400);
WIRE 16 -1 (-650 1650)(-200 1650);
WIRE 16 -1 (-650 1700)(-200 1700);
WIRE 16 -1 (-650 1750)(-200 1750);
WIRE 16 -1 (-650 1800)(-200 1800);
WIRE 16 -1 (-650 1850)(-200 1850);
WIRE 16 -1 (-650 -150)(-200 -150);
WIRE 16 -1 (-650 -200)(-200 -200);
WIRE 16 -1 (-650 -50)(-200 -50);
WIRE 16 -1 (-650 -100)(-200 -100);
WIRE 16 -1 (-650 4000)(-200 4000);
WIRE 16 -1 (-650 3950)(-200 3950);
WIRE 16 -1 (-650 3900)(-200 3900);
WIRE 16 -1 (-650 3850)(-200 3850);
WIRE 16 -1 (-650 3800)(-200 3800);
WIRE 16 -1 (-650 3750)(-200 3750);
WIRE 16 -1 (-650 3700)(-200 3700);
WIRE 16 -1 (-650 3650)(-200 3650);
WIRE 16 -1 (-650 3600)(-200 3600);
WIRE 16 -1 (-650 3550)(-200 3550);
WIRE 16 -1 (-650 3350)(-200 3350);
WIRE 16 -1 (-650 3300)(-200 3300);
WIRE 16 -1 (-650 3250)(-200 3250);
WIRE 16 -1 (-650 3200)(-200 3200);
WIRE 16 -1 (-650 3150)(-200 3150);
WIRE 16 -1 (-650 3100)(-200 3100);
WIRE 16 -1 (-650 3050)(-200 3050);
WIRE 16 -1 (-650 3000)(-200 3000);
WIRE 16 -1 (-650 2950)(-200 2950);
WIRE 16 -1 (-650 2900)(-200 2900);
WIRE 16 -1 (-650 2850)(-200 2850);
WIRE 16 -1 (-650 2800)(-200 2800);
WIRE 16 -1 (-650 2750)(-200 2750);
WIRE 16 -1 (-650 2700)(-200 2700);
WIRE 16 -1 (-650 2650)(-200 2650);
WIRE 16 -1 (-650 2600)(-200 2600);
WIRE 16 -1 (-650 2550)(-200 2550);
WIRE 16 -1 (-650 2500)(-200 2500);
WIRE 16 -1 (-650 2450)(-200 2450);
WIRE 16 -1 (-650 2400)(-200 2400);
WIRE 16 -1 (-650 2350)(-200 2350);
WIRE 16 -1 (-650 2300)(-200 2300);
WIRE 16 -1 (-650 2250)(-200 2250);
WIRE 16 -1 (-650 2200)(-200 2200);
WIRE 16 -1 (-650 2150)(-200 2150);
WIRE 16 -1 (-650 2100)(-200 2100);
WIRE 16 -1 (-650 2050)(-200 2050);
WIRE 16 -1 (-650 2000)(-200 2000);
WIRE 16 -1 (-650 1950)(-200 1950);
WIRE 16 -1 (-650 1900)(-200 1900);
WIRE 16 -1 (-650 1600)(-200 1600);
WIRE 16 -1 (-650 1550)(-200 1550);
WIRE 16 -1 (-650 1500)(-200 1500);
WIRE 16 -1 (-650 1450)(-200 1450);
WIRE 16 -1 (-650 1400)(-200 1400);
WIRE 16 -1 (-650 1350)(-200 1350);
WIRE 16 -1 (-650 1300)(-200 1300);
WIRE 16 -1 (-650 1250)(-200 1250);
WIRE 16 -1 (-650 1200)(-200 1200);
WIRE 16 -1 (-650 1150)(-200 1150);
WIRE 16 -1 (-650 1100)(-200 1100);
WIRE 16 -1 (-650 1050)(-200 1050);
WIRE 16 -1 (-650 1000)(-200 1000);
WIRE 16 -1 (-650 950)(-200 950);
WIRE 16 -1 (-650 900)(-200 900);
WIRE 16 -1 (-650 850)(-200 850);
WIRE 16 -1 (-650 800)(-200 800);
WIRE 16 -1 (-650 750)(-200 750);
WIRE 16 -1 (-650 700)(-200 700);
WIRE 16 -1 (-650 650)(-200 650);
WIRE 16 -1 (-650 600)(-200 600);
WIRE 16 -1 (-650 550)(-200 550);
WIRE 16 -1 (-650 500)(-200 500);
WIRE 16 -1 (-650 450)(-200 450);
WIRE 16 -1 (-650 400)(-200 400);
WIRE 16 -1 (-650 350)(-200 350);
WIRE 16 -1 (-650 300)(-200 300);
WIRE 16 -1 (-650 250)(-200 250);
WIRE 16 -1 (-650 200)(-200 200);
WIRE 16 -1 (-650 150)(-200 150);
WIRE 16 -1 (-650 100)(-200 100);
WIRE 16 -1 (-650 50)(-200 50);
WIRE 16 -1 (3775 850)(2250 850);
FORCEPROP 2 LAST SIG_NAME M_E_CPU0_SB_PAR
J 0
(2884 859);
DISPLAY 0.680851 (2884 859);
PAINT WHITE (2884 859);
WIRE 16 -1 (2250 2400)(2675 2400);
WIRE 16 -1 (2250 2450)(2675 2450);
WIRE 16 -1 (2250 2500)(2675 2500);
WIRE 16 -1 (2250 2550)(2675 2550);
WIRE 16 -1 (2250 2600)(2675 2600);
WIRE 16 -1 (2250 2650)(2675 2650);
WIRE 16 -1 (2250 2700)(2675 2700);
WIRE 16 -1 (2250 2750)(2675 2750);
WIRE 16 -1 (2250 2800)(2675 2800);
WIRE 16 -1 (2250 2850)(2675 2850);
WIRE 16 -1 (2250 1850)(2675 1850);
WIRE 16 -1 (2250 1900)(2675 1900);
WIRE 16 -1 (2250 1950)(2675 1950);
WIRE 16 -1 (2250 2000)(2675 2000);
WIRE 16 -1 (2250 2050)(2675 2050);
WIRE 16 -1 (2250 2100)(2675 2100);
WIRE 16 -1 (2250 2150)(2675 2150);
WIRE 16 -1 (2250 2200)(2675 2200);
WIRE 16 -1 (2250 2250)(2675 2250);
WIRE 16 -1 (2250 2300)(2675 2300);
WIRE 16 -1 (2250 250)(2675 250);
WIRE 16 -1 (2250 300)(2675 300);
WIRE 16 -1 (2250 350)(2675 350);
WIRE 16 -1 (2250 400)(2675 400);
WIRE 16 -1 (2250 900)(2675 900);
WIRE 16 -1 (2250 950)(2675 950);
WIRE 16 -1 (2250 1000)(2675 1000);
WIRE 16 -1 (2250 1050)(2675 1050);
WIRE 16 -1 (2250 1100)(2675 1100);
WIRE 16 -1 (2250 1150)(2675 1150);
WIRE 16 -1 (2250 1200)(2675 1200);
WIRE 16 -1 (3775 1350)(2250 1350);
FORCEPROP 2 LAST SIG_NAME M_E_CPU0_SA_PAR
J 0
(2884 1359);
DISPLAY 0.680851 (2884 1359);
PAINT WHITE (2884 1359);
WIRE 16 -1 (2250 3550)(2675 3550);
WIRE 16 -1 (2250 3600)(2675 3600);
WIRE 16 -1 (2250 3650)(2675 3650);
WIRE 16 -1 (2250 3700)(2675 3700);
WIRE 16 -1 (2250 3750)(2675 3750);
WIRE 16 -1 (2250 3800)(2675 3800);
WIRE 16 -1 (2250 3850)(2675 3850);
WIRE 16 -1 (2250 3900)(2675 3900);
WIRE 16 -1 (2250 3950)(2675 3950);
WIRE 16 -1 (2250 4000)(2675 4000);
WIRE 16 -1 (2250 3000)(2675 3000);
WIRE 16 -1 (2250 3050)(2675 3050);
WIRE 16 -1 (2250 3100)(2675 3100);
WIRE 16 -1 (2250 3150)(2675 3150);
WIRE 16 -1 (2250 3200)(2675 3200);
WIRE 16 -1 (2250 3250)(2675 3250);
WIRE 16 -1 (2250 3300)(2675 3300);
WIRE 16 -1 (2250 3350)(2675 3350);
WIRE 16 -1 (2250 3400)(2675 3400);
WIRE 16 -1 (2250 3450)(2675 3450);
WIRE 16 -1 (2250 550)(2675 550);
WIRE 16 -1 (2250 600)(2675 600);
WIRE 16 -1 (2250 650)(2675 650);
WIRE 16 -1 (2250 700)(2675 700);
WIRE 16 -1 (2250 1400)(2675 1400);
WIRE 16 -1 (2250 1450)(2675 1450);
WIRE 16 -1 (2250 1500)(2675 1500);
WIRE 16 -1 (2250 1550)(2675 1550);
WIRE 16 -1 (2250 1600)(2675 1600);
WIRE 16 -1 (2250 1650)(2675 1650);
WIRE 16 -1 (2250 1700)(2675 1700);
WIRE 16 -1 (3775 -100)(2250 -100);
FORCEPROP 2 LAST SIG_NAME M_E_CPU0_SB_RSP<0>
J 0
(2884 -91);
DISPLAY 0.680851 (2884 -91);
PAINT WHITE (2884 -91);
WIRE 16 -1 (3775 -50)(2250 -50);
FORCEPROP 2 LAST SIG_NAME M_E_CPU0_SB_RSP<1>
J 0
(2884 -41);
DISPLAY 0.680851 (2884 -41);
PAINT WHITE (2884 -41);
WIRE 16 -1 (3775 50)(2250 50);
FORCEPROP 2 LAST SIG_NAME M_E_CPU0_SA_RSP<0>
J 0
(2884 59);
DISPLAY 0.680851 (2884 59);
PAINT WHITE (2884 59);
WIRE 16 -1 (3775 100)(2250 100);
FORCEPROP 2 LAST SIG_NAME M_E_CPU0_SA_RSP<1>
J 0
(2884 109);
DISPLAY 0.680851 (2884 109);
PAINT WHITE (2884 109);
WIRE 16 -1 (3775 -200)(2250 -200);
FORCEPROP 2 LAST SIG_NAME M_E_CPU0_ALERT_N
J 0
(2884 -191);
DISPLAY 0.680851 (2884 -191);
PAINT WHITE (2884 -191);
QUIT
